G04 ================== begin FILE IDENTIFICATION RECORD ==================*
G04 Layout Name:  D:/<user>/Wistron_project/16316-1/gbr-0621/16316-1.brd*
G04 Film Name:    L3*
G04 File Format:  Gerber RS274X*
G04 File Origin:  Cadence Allegro 16.5-S056*
G04 Origin Date:  Wed Jun 21 09:32:05 2017*
G04 *
G04 Layer:  VIA CLASS/L3*
G04 Layer:  PIN/L3*
G04 Layer:  ETCH/L3*
G04 Layer:  DRAWING FORMAT/LAYER_PCB_STORY*
G04 Layer:  DRAWING FORMAT/LAYER_L3*
G04 *
G04 Offset:    (0.00 0.00)*
G04 Mirror:    No*
G04 Mode:      Positive*
G04 Rotation:  0*
G04 FullContactRelief:  No*
G04 UndefLineWidth:     6.00*
G04 ================== end FILE IDENTIFICATION RECORD ====================*
%FSLAX35Y35*MOIN*%
%IR0*IPPOS*OFA0.00000B0.00000*MIA0B0*SFA1.00000B1.00000*%
%ADD11C,.02*%
%ADD12C,.03*%
%ADD13C,.018*%
%ADD10C,.028*%
%ADD14C,.01*%
%ADD15C,.04*%
%ADD16C,.004*%
%ADD17C,.005*%
%ADD18C,.006*%
%ADD19C,.0035*%
%ADD23C,.03004*%
%ADD21C,.05204*%
%ADD20C,.04404*%
%ADD22C,.02804*%
G75*
%LPD*%
G75*
G36*
G01X443151Y493059D02*
X476035Y498319D01*
G03X495140Y520723I-3584J22404D01*
G01Y562992D01*
G02X500010Y567862I4870J0D01*
G01X818898D01*
G02X823768Y562992I0J-4870D01*
G01Y7874D01*
G02X818898Y3004I-4870J0D01*
G01X168082D01*
Y8000D01*
X344155D01*
G03X347185I1515J2237D01*
G01X358328D01*
G03X361358I1515J2237D01*
G01X372501D01*
G03X375531I1515J2237D01*
G01X386674D01*
G03X389704I1515J2237D01*
G01X400848D01*
G03X403878I1515J2237D01*
G01X415021D01*
G03X418051I1515J2237D01*
G01X429194D01*
G03X432224I1515J2237D01*
G01X443367D01*
G03X446397I1515J2237D01*
G01X457540D01*
G03X460570I1515J2237D01*
G01X471714D01*
G03X474744I1515J2237D01*
G01X485887D01*
G03X488917I1515J2237D01*
G01X500060D01*
G03X503090I1515J2237D01*
G01X514233D01*
G03X517263I1515J2237D01*
G01X528407D01*
G03X531437I1515J2237D01*
G01X542580D01*
G03X545610I1515J2237D01*
G01X556753D01*
G03X559783I1515J2237D01*
G01X570926D01*
G03X573956I1515J2237D01*
G01X585099D01*
G03X588129I1515J2237D01*
G01X714233D01*
G03X717263I1515J2237D01*
G01X728406D01*
G03X731436I1515J2237D01*
G01X742579D01*
G03X745609I1515J2237D01*
G01X756752D01*
G03X759782I1515J2237D01*
G01X818772D01*
Y562866D01*
X500136D01*
Y520723D01*
G02X476824Y493386I-27685J1D01*
G01X443548Y488063D01*
X383223D01*
X349967Y493383D01*
G02X326656Y520719I4374J27337D01*
G01Y563116D01*
X7896D01*
X7750Y562970D01*
Y562762D01*
X7896Y562616D01*
X8000D01*
Y8000D01*
X102995D01*
Y3004D01*
X7874D01*
G02X3004Y7874I0J4870D01*
G01Y562992D01*
G02X7874Y567862I4870J0D01*
G01X326783D01*
G02X331650Y563117I-1J-4870D01*
G01Y562616D01*
X331652D01*
Y520719D01*
G03X350756Y498316I22689J1D01*
G01X383620Y493059D01*
X443151D01*
G37*
G36*
G01X248593Y51744D02*
X235935Y64402D01*
X235946Y64498D01*
G03X233505Y66939I-2187J254D01*
G01X233409Y66928D01*
X224299Y76038D01*
X138162D01*
X112200Y102000D01*
Y141400D01*
X96100Y157500D01*
Y258700D01*
X94400Y260400D01*
Y260518D01*
X88118Y266800D01*
X18800D01*
X17000Y268600D01*
Y406000D01*
X20000Y409000D01*
X159800D01*
X165900Y415100D01*
Y492400D01*
X172100Y498600D01*
X225000D01*
X226900Y496700D01*
Y483200D01*
X225400Y481700D01*
X199300D01*
X196600Y479000D01*
Y369600D01*
X177300Y350300D01*
X177100D01*
X114100Y287300D01*
Y172500D01*
X132200Y154400D01*
Y137466D01*
X153750Y115916D01*
Y101956D01*
X161606Y94100D01*
X199500D01*
X211500Y106100D01*
X247998D01*
X286968Y67130D01*
Y58267D01*
X286967Y58258D01*
G03Y57878I2194J-190D01*
G01X286968Y57869D01*
Y52476D01*
X286236Y51744D01*
X248593D01*
G37*
G36*
G01X342500Y210000D02*
X341000D01*
X340500Y210500D01*
Y213500D01*
X339887Y214113D01*
X333551D01*
Y220911D01*
X333911D01*
X334500Y221500D01*
Y225000D01*
X335000Y225500D01*
X336500D01*
X337000Y225000D01*
Y221500D01*
X337589Y220911D01*
X343907D01*
Y214113D01*
X343613D01*
X343000Y213500D01*
Y210500D01*
X342500Y210000D01*
G37*
G36*
G01X432100Y241500D02*
X430698Y242902D01*
Y263110D01*
X430712Y263146D01*
G03Y264416I-1578J635D01*
G01X430698Y264452D01*
Y272909D01*
X432240Y274451D01*
X432373Y274375D01*
G03X434204Y276416I698J1216D01*
G01X436141Y278353D01*
G03X438062Y280391I916J1061D01*
G01X439871Y282200D01*
X440339D01*
X440378Y282183D01*
G03X441512I567J1282D01*
G01X441551Y282200D01*
X448213D01*
X448252Y282183D01*
G03X449386I567J1282D01*
G01X449425Y282200D01*
X460024D01*
X460063Y282183D01*
G03X461197I567J1282D01*
G01X461236Y282200D01*
X467898D01*
X467937Y282183D01*
G03X469071I567J1282D01*
G01X469110Y282200D01*
X471835D01*
X471874Y282183D01*
G03X473008I567J1282D01*
G01X473047Y282200D01*
X479709D01*
X479748Y282183D01*
G03X480882I567J1282D01*
G01X480921Y282200D01*
X487583D01*
X487622Y282183D01*
G03X488756I567J1282D01*
G01X488795Y282200D01*
X491520D01*
X491559Y282183D01*
G03X493520Y283615I567J1282D01*
G01X493510Y283710D01*
X495693Y285893D01*
X497207D01*
X497304Y285990D01*
X500000D01*
G03X501401Y287234I0J1411D01*
G01X501412Y287318D01*
Y287412D01*
G03X501270Y288018I-1412J-11D01*
G01X501208Y288146D01*
X503200Y290138D01*
X503328Y290076D01*
G03X505071Y292164I609J1263D01*
G01X507049Y294142D01*
G03X509237Y295605I825J1134D01*
G02X509626Y296099I389J94D01*
G01X516655D01*
G03X518345I845J1119D01*
G01X534719D01*
X534749Y296089D01*
G03X534813Y296078I66J191D01*
G01X538013D01*
G03X538077Y296089I-2J202D01*
G01X538107Y296099D01*
X549967D01*
X550002Y296134D01*
X554082D01*
X561543Y303595D01*
X580605D01*
X581400Y302800D01*
Y262800D01*
X579548Y260948D01*
X531685D01*
X519100Y248363D01*
Y243600D01*
X517000Y241500D01*
X516155D01*
X516128Y241507D01*
G03X515368I-380J-1349D01*
G01X515341Y241500D01*
X512249D01*
X512221Y241509D01*
G03X511811Y241570I-411J-1351D01*
G01X507874D01*
G03X507464Y241509I1J-1412D01*
G01X507436Y241500D01*
X504344D01*
X504317Y241507D01*
G03X503557I-380J-1349D01*
G01X503530Y241500D01*
X500438D01*
X500410Y241509D01*
G03X500000Y241570I-411J-1351D01*
G01X496063D01*
G03X495653Y241509I1J-1412D01*
G01X495625Y241500D01*
X492533D01*
X492506Y241507D01*
G03X491746I-380J-1349D01*
G01X491719Y241500D01*
X488596D01*
X488569Y241507D01*
G03X487809I-380J-1349D01*
G01X487782Y241500D01*
X480722D01*
X480695Y241507D01*
G03X479935I-380J-1349D01*
G01X479908Y241500D01*
X472848D01*
X472821Y241507D01*
G03X472061I-380J-1349D01*
G01X472034Y241500D01*
X464974D01*
X464947Y241507D01*
G03X464187I-380J-1349D01*
G01X464160Y241500D01*
X457100D01*
X457073Y241507D01*
G03X456313I-380J-1349D01*
G01X456286Y241500D01*
X449226D01*
X449199Y241507D01*
G03X448439I-380J-1349D01*
G01X448412Y241500D01*
X441352D01*
X441325Y241507D01*
G03X440565I-380J-1349D01*
G01X440538Y241500D01*
X433478D01*
X433451Y241507D01*
G03X432691I-380J-1349D01*
G01X432664Y241500D01*
X432100D01*
G37*
G36*
G01X628914Y171293D02*
X622116D01*
Y171884D01*
X622000Y172000D01*
X617500D01*
X617000Y172500D01*
Y174000D01*
X617500Y174500D01*
X622000D01*
X622116Y174616D01*
Y181649D01*
X625649D01*
X626000Y182000D01*
Y186000D01*
X626500Y186500D01*
X628000D01*
X628500Y186000D01*
Y181900D01*
X628751Y181649D01*
X628914D01*
Y171293D01*
G37*
G36*
G01X680600Y251100D02*
X670800Y241300D01*
X655200D01*
X621400Y275100D01*
Y316419D01*
X622081Y317100D01*
X627724D01*
X630243Y314580D01*
G03X633397Y314622I1557J1557D01*
G02X633970Y314630I290J-275D01*
G01X667171Y281429D01*
X667115Y281304D01*
G03X670146Y278454I2010J-899D01*
G01X680600Y268000D01*
Y251100D01*
G37*
G36*
G01X630450Y386200D02*
X629550Y387100D01*
Y396750D01*
X632850Y400050D01*
Y415250D01*
X639000Y421400D01*
Y441500D01*
X650300Y452800D01*
Y479000D01*
X661400Y490100D01*
X690700D01*
X691800Y489000D01*
Y480200D01*
X691100Y479500D01*
X671200D01*
X662600Y470900D01*
Y446600D01*
X649600Y433600D01*
Y429198D01*
G03Y429002I2600J-98D01*
G01Y407700D01*
X640050Y398150D01*
Y387150D01*
X639100Y386200D01*
X630450D01*
G37*
G36*
G01X671761Y100002D02*
G03X668899Y100320I-1615J-1497D01*
G01X668762Y100225D01*
X661023Y107964D01*
Y115080D01*
X661153Y115128D01*
G03Y117944I-524J1408D01*
G01X661023Y117992D01*
Y118323D01*
X661149Y118373D01*
G03X661856Y118988I-520J1312D01*
G02X662552I348J-198D01*
G03X665180Y119517I1227J697D01*
G01X665190Y119601D01*
Y122844D01*
G03X662552Y123532I-1411J-10D01*
G02X661857I-348J198D01*
G03X660558Y124244I-1227J-698D01*
G01X660469Y124239D01*
X660085Y124623D01*
Y134927D01*
X662284Y137126D01*
X662385D01*
G02X662678Y136454I0J-400D01*
G03X662935Y134188I1100J-1023D01*
G02Y133526I-224J-331D01*
G03X664622I843J-1243D01*
G02Y134188I224J331D01*
G03X664878Y136454I-844J1243D01*
G02X665171Y137126I293J272D01*
G01X666554D01*
X666577Y137120D01*
G03X667279I351J1461D01*
G01X667302Y137126D01*
X672853D01*
X672876Y137120D01*
G03X673578I351J1461D01*
G01X673601Y137126D01*
X674982D01*
G02X675276Y136455I0J-400D01*
G03X675538Y134190I1103J-1020D01*
G02Y133527I-224J-331D01*
G03X677217Y133526I839J-1246D01*
G02Y134189I224J331D01*
G03X677482Y136455I-838J1246D01*
G02X677776Y137126I294J271D01*
G01X679152D01*
X679175Y137120D01*
G03X679877I351J1461D01*
G01X679900Y137126D01*
X681282D01*
G02X681576Y136455I0J-400D01*
G03X681911Y134144I1103J-1020D01*
G02X681921Y133463I-205J-344D01*
G03X683432Y133461I754J-1182D01*
G02X683444Y134142I216J337D01*
G03X683782Y136455I-765J1293D01*
G02X684076Y137126I294J271D01*
G01X685451D01*
X685474Y137120D01*
G03X686176I351J1461D01*
G01X686199Y137126D01*
X687581D01*
G02X687875Y136455I0J-400D01*
G03X688210Y134144I1103J-1020D01*
G02X688220Y133463I-205J-344D01*
G03X689731Y133461I754J-1182D01*
G02X689743Y134142I216J337D01*
G03X690219Y134589I-766J1292D01*
G02X690881Y134588I331J-225D01*
G03X693050Y134249I1243J843D01*
G01X693190Y134358D01*
X696904Y130644D01*
Y115241D01*
X697885Y114260D01*
X741658D01*
X741708Y114135D01*
G03X744492I1392J565D01*
G01X744542Y114260D01*
X767092D01*
X769698Y111654D01*
Y102522D01*
X767178Y100002D01*
X755407D01*
G02X755014Y100479I0J400D01*
G03X750692I-2161J421D01*
G02X750299Y100002I-393J-77D01*
G01X727450D01*
X727444Y100196D01*
G03X724442I-1501J-49D01*
G01X724436Y100002D01*
X712980D01*
G02X712580Y100402I0J400D01*
G03X708176I-2202J-3D01*
G02X707776Y100002I-400J0D01*
G01X704010D01*
G03X700772I-1619J-1492D01*
G01X695935D01*
G03X692795I-1570J-1544D01*
G01X687884D01*
G03X684674I-1605J-1508D01*
G01X679831D01*
G03X676619I-1606J-1506D01*
G01X671761D01*
G37*
%LPC*%
G75*
G36*
G01X174949Y442616D02*
G03X174934Y443285I-227J330D01*
G02X177785Y443349I1377J2208D01*
G03X177800Y442680I227J-330D01*
G02X174949Y442616I-1377J-2208D01*
G37*
G36*
G01X67108Y380304D02*
G03X67692I292J274D01*
G02Y377296I1608J-1504D01*
G03X67108I-292J-274D01*
G02Y380304I-1608J1504D01*
G37*
G36*
G01X88160Y377070D02*
G03X87530I-315J-246D01*
G02Y379782I-1735J1356D01*
G03X88160I315J246D01*
G02Y377070I1735J-1356D01*
G37*
G36*
G01X23735Y379708D02*
G03X24365I315J246D01*
G02Y376996I1735J-1356D01*
G03X23735I-315J-246D01*
G02Y379708I-1735J1356D01*
G37*
G36*
G01X45250Y376775D02*
G03X44650I-300J-265D01*
G02Y379691I-1650J1458D01*
G03X45250I300J265D01*
G02Y376775I1650J-1458D01*
G37*
G36*
G01X38280Y362160D02*
G03X37620I-330J-226D01*
G02Y364640I-1820J1240D01*
G03X38280I330J226D01*
G02Y362160I1820J-1240D01*
G37*
G36*
G01X80478Y361786D02*
G03X79864I-307J-255D01*
G02Y364604I-1693J1409D01*
G03X80478I307J255D01*
G02Y361786I1693J-1409D01*
G37*
G36*
G01X101573Y361579D02*
G03X100959I-307J-255D01*
G02Y364397I-1693J1409D01*
G03X101573I307J255D01*
G02Y361579I1693J-1409D01*
G37*
G36*
G01X82103Y336189D02*
G03X82630Y336172I273J292D01*
G02X82522Y332859I1395J-1704D01*
G03X81995Y332876I-273J-292D01*
G02X82103Y336189I-1395J1704D01*
G37*
G36*
G01X39403Y335989D02*
G03X39930Y335972I273J292D01*
G02X39822Y332659I1395J-1704D01*
G03X39295Y332676I-273J-292D01*
G02X39403Y335989I-1395J1704D01*
G37*
G36*
G01X60403Y335789D02*
G03X60930Y335772I273J292D01*
G02X60822Y332459I1395J-1704D01*
G03X60295Y332476I-273J-292D01*
G02X60403Y335789I-1395J1704D01*
G37*
G36*
G01X29960Y332428D02*
G03X29422Y332431I-271J-294D01*
G02X29437Y335688I-1475J1635D01*
G03X29975Y335685I271J294D01*
G02X29960Y332428I1475J-1635D01*
G37*
G36*
G01X77419Y319191D02*
G03X77403Y319852I-233J325D01*
G02X79881Y319909I1197J1848D01*
G03X79897Y319248I233J-325D01*
G02X77419Y319191I-1197J-1848D01*
G37*
G36*
G01X35482Y275552D02*
G03X36107I312J249D01*
G02Y272808I1723J-1372D01*
G03X35482I-312J-249D01*
G02Y275552I-1723J1372D01*
G37*
G36*
G01X256775Y70965D02*
G03X256763Y70680I134J-148D01*
G02X253679Y70812I-1609J-1503D01*
G03X253691Y71097I-134J148D01*
G02X256775Y70965I1609J1503D01*
G37*
G36*
G01X259806Y53944D02*
G03X259192I-307J-255D01*
G02Y56762I-1693J1409D01*
G03X259806I307J255D01*
G02Y53944I1693J-1409D01*
G37*
G36*
G01X103192Y331113D02*
G02X101493Y331149I-893J-2013D01*
G03X101508Y331887I-147J372D01*
G02X104135Y335256I892J2013D01*
G03X104765I315J246D01*
G02Y332544I1735J-1356D01*
G03X104135I-315J-246D01*
G02X103207Y331851I-1735J1356D01*
G03X103192Y331113I147J-372D01*
G37*
G36*
G01X24206Y315904D02*
G02X21994I-1106J-1904D01*
G03Y316596I-201J346D01*
G02X24206I1106J1904D01*
G03Y315904I201J-346D01*
G37*
G36*
G01X81492Y306613D02*
G02X79793Y306649I-893J-2013D01*
G03X79808Y307387I-147J372D01*
G02X81507Y307351I893J2013D01*
G03X81492Y306613I147J-372D01*
G37*
G36*
G01X24206Y289604D02*
G02X21994I-1106J-1904D01*
G03Y290296I-201J346D01*
G02X24206I1106J1904D01*
G03Y289604I201J-346D01*
G37*
G36*
G01X515748Y285990D02*
X511810D01*
G02X511811Y288814I1J1412D01*
G01X515748D01*
G02X517160Y287412I0J-1412D01*
G01Y287318D01*
X517149Y287234D01*
G02X515748Y285990I-1401J167D01*
G37*
G36*
G01X511811Y282054D02*
X507873D01*
G02X507874Y284876I1J1411D01*
G01X511811D01*
G02X513222Y283475I0J-1411D01*
G01Y283381D01*
X513212Y283297D01*
G02X511811Y282054I-1401J168D01*
G37*
G36*
G01X500000D02*
X496062D01*
G02X496063Y284876I1J1411D01*
G01X500000D01*
G02X501412Y283475I0J-1412D01*
G01Y283381D01*
X501401Y283297D01*
G02X500000Y282054I-1401J168D01*
G37*
G36*
G01X515748Y278116D02*
X511810D01*
G02X511811Y280940I1J1412D01*
G01X515748D01*
G02X517160Y279538I0J-1412D01*
G01Y279444D01*
X517149Y279360D01*
G02X515748Y278116I-1401J167D01*
G37*
G36*
G01X500000D02*
X496062D01*
G02X496063Y280940I1J1412D01*
G01X500000D01*
G02X501412Y279538I0J-1412D01*
G01Y279444D01*
X501401Y279360D01*
G02X500000Y278116I-1401J167D01*
G37*
G36*
G01X511811Y274180D02*
X507873D01*
G02X507874Y277002I1J1411D01*
G01X511811D01*
G02X513222Y275601I0J-1411D01*
G01Y275507D01*
X513212Y275423D01*
G02X511811Y274180I-1401J168D01*
G37*
G36*
G01X500000D02*
X496062D01*
G02X496063Y277002I1J1411D01*
G01X500000D01*
G02X501412Y275601I0J-1412D01*
G01Y275507D01*
X501401Y275423D01*
G02X500000Y274180I-1401J168D01*
G37*
G36*
G01X515748Y270242D02*
X511810D01*
G02X511811Y273066I1J1412D01*
G01X515748D01*
G02X517160Y271664I0J-1412D01*
G01Y271570D01*
X517149Y271486D01*
G02X515748Y270242I-1401J167D01*
G37*
G36*
G01X500000D02*
X496062D01*
G02X496063Y273066I1J1412D01*
G01X500000D01*
G02X501412Y271664I0J-1412D01*
G01Y271570D01*
X501401Y271486D01*
G02X500000Y270242I-1401J167D01*
G37*
G36*
G01X511811Y266306D02*
X507873D01*
G02X507874Y269128I1J1411D01*
G01X511811D01*
G02X513222Y267727I0J-1411D01*
G01Y267633D01*
X513212Y267549D01*
G02X511811Y266306I-1401J168D01*
G37*
G36*
G01X500000D02*
X496062D01*
G02X496063Y269128I1J1411D01*
G01X500000D01*
G02X501412Y267727I0J-1412D01*
G01Y267633D01*
X501401Y267549D01*
G02X500000Y266306I-1401J168D01*
G37*
G36*
G01X515748Y258432D02*
X511810D01*
G02X511811Y261254I1J1411D01*
G01X515748D01*
G02X517160Y259853I0J-1412D01*
G01Y259759D01*
X517149Y259675D01*
G02X515748Y258432I-1401J168D01*
G37*
G36*
G01X500000D02*
X496062D01*
G02X496063Y261254I1J1411D01*
G01X500000D01*
G02X501412Y259853I0J-1412D01*
G01Y259759D01*
X501401Y259675D01*
G02X500000Y258432I-1401J168D01*
G37*
G36*
G01X511811Y254494D02*
X507873D01*
G02X507874Y257318I1J1412D01*
G01X511811D01*
G02X513222Y255916I0J-1411D01*
G01Y255822D01*
X513212Y255738D01*
G02X511811Y254494I-1401J167D01*
G37*
G36*
G01X500000D02*
X496062D01*
G02X496063Y257318I1J1412D01*
G01X500000D01*
G02X501412Y255916I0J-1412D01*
G01Y255822D01*
X501401Y255738D01*
G02X500000Y254494I-1401J167D01*
G37*
G36*
G01X515748Y250558D02*
X511810D01*
G02X511811Y253380I1J1411D01*
G01X515748D01*
G02X517160Y251979I0J-1412D01*
G01Y251885D01*
X517149Y251801D01*
G02X515748Y250558I-1401J168D01*
G37*
G36*
G01X500000D02*
X496062D01*
G02X496063Y253380I1J1411D01*
G01X500000D01*
G02X501412Y251979I0J-1412D01*
G01Y251885D01*
X501401Y251801D01*
G02X500000Y250558I-1401J168D01*
G37*
G36*
G01X511811Y246620D02*
X507873D01*
G02X507874Y249444I1J1412D01*
G01X511811D01*
G02X513222Y248042I0J-1411D01*
G01Y247948D01*
X513212Y247864D01*
G02X511811Y246620I-1401J167D01*
G37*
G36*
G01X500000D02*
X496062D01*
G02X496063Y249444I1J1412D01*
G01X500000D01*
G02X501412Y248042I0J-1412D01*
G01Y247948D01*
X501401Y247864D01*
G02X500000Y246620I-1401J167D01*
G37*
G36*
G01X515748Y242684D02*
X511810D01*
G02X511811Y245506I1J1411D01*
G01X515748D01*
G02X517160Y244105I0J-1412D01*
G01Y244011D01*
X517149Y243927D01*
G02X515748Y242684I-1401J168D01*
G37*
G36*
G01X500000D02*
X496062D01*
G02X496063Y245506I1J1411D01*
G01X500000D01*
G02X501412Y244105I0J-1412D01*
G01Y244011D01*
X501401Y243927D01*
G02X500000Y242684I-1401J168D01*
G37*
G36*
G01X634400Y294183D02*
G03Y293653I300J-265D01*
G02X631100I-1650J-1458D01*
G03Y294183I-300J265D01*
G02X634400I1650J1458D01*
G37*
G36*
G01X664686Y251172D02*
G03X664671Y250634I288J-277D01*
G02X661414Y250728I-1671J-1434D01*
G03X661429Y251266I-288J277D01*
G02X664686Y251172I1671J1434D01*
G37*
G36*
G01X735850Y109009D02*
G03X735309Y108969I-249J-313D01*
G02X735147Y111171I-1097J1026D01*
G03X735688Y111211I249J313D01*
G02X735850Y109009I1097J-1026D01*
G37*
G36*
G01X718654Y109280D02*
G03X719035Y108783I388J-97D01*
G02X717553Y107647I-25J-1502D01*
G03X717172Y108144I-388J97D01*
G02X718654Y109280I25J1502D01*
G37*
G36*
G01X667771Y127228D02*
G02X666087I-842J-1244D01*
G03Y127890I-224J331D01*
G02X667771I842J1244D01*
G03Y127228I224J-331D01*
G37*
G36*
G01X687565Y119686D02*
Y122834D01*
G02X690204Y123533I1412J1D01*
G03X690899I347J198D01*
G02X693538Y122845I1227J-698D01*
G01Y119602D01*
X693527Y119518D01*
G02X690899Y118988I-1401J168D01*
G03X690203I-348J-197D01*
G02X687564Y119686I-1227J697D01*
G01X687565D01*
G37*
G36*
G01X678116D02*
Y122834D01*
G02X678762Y124021I1412J1D01*
G03X678752Y124699I-217J336D01*
G02X680304I776J1286D01*
G03X680294Y124021I207J-342D01*
G02X680755Y123532I-767J-1185D01*
G03X681451I348J198D01*
G02X684078Y123011I1227J-697D01*
G01X684090Y122924D01*
Y122834D01*
X684088Y120635D01*
Y119601D01*
X684078Y119517D01*
G02X681450Y118988I-1401J168D01*
G03X680754I-348J-198D01*
G02X678115Y119686I-1227J697D01*
G01X678116D01*
G37*
G36*
G01X671305Y118988D02*
G02X668666Y119686I-1227J697D01*
G01X668667D01*
Y122834D01*
G02X671306Y123532I1412J1D01*
G03X672002I348J198D01*
G02X672463Y124021I1228J-696D01*
G03X672453Y124699I-217J336D01*
G02X674005I776J1286D01*
G03X673995Y124021I207J-342D01*
G02X674629Y123011I-767J-1185D01*
G01X674640Y122924D01*
Y119601D01*
X674629Y119517D01*
G02X672001Y118988I-1401J168D01*
G03X671305I-348J-198D01*
G37*
G36*
G01X736599Y107427D02*
G02X736560Y105678I1201J-902D01*
G03X735910Y105693I-330J-226D01*
G02X735949Y107442I-1201J902D01*
G03X736599Y107427I330J226D01*
G37*
G54D23*
X688976Y113385D03*
X678189Y108784D03*
X689049Y109487D03*
X669500Y108400D03*
X685827Y125985D03*
X676377Y116536D03*
X666929Y116535D03*
X692148Y129119D03*
X670116Y132283D03*
X722673Y105444D03*
X726100Y107200D03*
X731000Y106315D03*
X699563Y108815D03*
X707649Y110002D03*
X710517Y106823D03*
X704849Y107385D03*
G54D21*
X177468Y417900D03*
X158067Y378857D03*
X177421Y432909D03*
X177532Y426134D03*
G54D20*
X69143Y334598D03*
X47443Y334198D03*
X37049Y302949D03*
X52450Y333850D03*
X74150Y334250D03*
X57350Y387800D03*
X31240Y393440D03*
X49700Y391000D03*
X54040Y399390D03*
X81000Y291700D03*
X80896Y286695D03*
X80688Y281695D03*
Y276695D03*
X90238Y334391D03*
X95245Y334043D03*
X83232Y399956D03*
X106709Y383400D03*
X112023Y383013D03*
X102679Y391150D03*
X112638Y391197D03*
X107582Y391266D03*
X229000Y95000D03*
X234450Y73000D03*
X245250Y98250D03*
X261102Y77900D03*
X248169Y74454D03*
X242727Y63391D03*
X267188Y55192D03*
X277514Y58068D03*
X276700Y66700D03*
X634000Y306300D03*
X674841Y262854D03*
X644153Y278745D03*
X660400Y271900D03*
G54D22*
X433070Y255905D03*
X433071Y248032D03*
X444882Y279529D03*
X448819Y248032D03*
X440945D03*
X448818Y259843D03*
Y267718D03*
X440944D03*
X433071Y263781D03*
X440944Y259843D03*
X437008Y275591D03*
X444882D03*
X437007Y267718D03*
X448818Y255906D03*
Y263780D03*
Y271655D03*
X440944Y263780D03*
Y271655D03*
X437007Y259843D03*
Y255905D03*
X440944Y255906D03*
X503937D03*
X507874Y251969D03*
X503937Y248032D03*
X507874Y244095D03*
Y271654D03*
X503937Y267717D03*
X507874Y259843D03*
Y287402D03*
X503937Y283465D03*
X507874Y279528D03*
X503937Y275591D03*
X484252Y271654D03*
Y279528D03*
X488189Y267717D03*
Y275591D03*
X492126Y271654D03*
Y279528D03*
X484252Y259843D03*
Y251969D03*
Y244095D03*
X492126Y259843D03*
Y251969D03*
Y244095D03*
X456693Y279528D03*
Y267718D03*
X464567D03*
X503937Y251969D03*
Y244095D03*
Y271654D03*
Y259843D03*
Y287402D03*
Y279528D03*
X456693Y259843D03*
X480315Y267717D03*
Y271654D03*
Y275591D03*
Y279528D03*
X492126Y267717D03*
X488189Y271654D03*
X492126Y275591D03*
X488189Y279528D03*
X480315Y259843D03*
Y244095D03*
Y248032D03*
Y251969D03*
Y255906D03*
X488189Y259843D03*
X492126Y248032D03*
X488189D03*
Y255906D03*
X452757Y279529D03*
X464567D03*
X472441Y275591D03*
Y267717D03*
Y259843D03*
Y251969D03*
X456693Y248032D03*
X464567D03*
Y259843D03*
X460630Y275592D03*
X464568D03*
X452756D03*
X456693Y255906D03*
X464567D03*
Y263780D03*
X456693D03*
X464567Y271655D03*
X456693D03*
X518647Y288943D03*
X515748Y267717D03*
Y255906D03*
Y248032D03*
Y283465D03*
Y275591D03*
%LPD*%
G75*
G54D10*
X15364Y5500D03*
X10364D03*
X5500Y10384D03*
Y15384D03*
Y20384D03*
Y25384D03*
Y30384D03*
Y35384D03*
Y40384D03*
Y45384D03*
Y50384D03*
Y55384D03*
Y60384D03*
Y65384D03*
Y70384D03*
Y75384D03*
Y80384D03*
Y85384D03*
Y90384D03*
Y95384D03*
Y100384D03*
Y105384D03*
Y110384D03*
Y115384D03*
Y120384D03*
Y125384D03*
Y130384D03*
Y135384D03*
Y140384D03*
Y145384D03*
Y150384D03*
Y155384D03*
Y160384D03*
Y165384D03*
Y170384D03*
Y175384D03*
Y180384D03*
Y185384D03*
Y190384D03*
Y195384D03*
Y200384D03*
Y205384D03*
Y210384D03*
Y215384D03*
Y220384D03*
Y225384D03*
Y230384D03*
Y235384D03*
Y240384D03*
Y245384D03*
Y250384D03*
Y255384D03*
Y260384D03*
Y265384D03*
Y270384D03*
Y275384D03*
Y280384D03*
Y285384D03*
Y290384D03*
Y295384D03*
Y300384D03*
Y305384D03*
Y310384D03*
Y315384D03*
Y320384D03*
Y325384D03*
Y330384D03*
Y335384D03*
Y340384D03*
Y345384D03*
Y350384D03*
Y355384D03*
Y360384D03*
Y365384D03*
Y370384D03*
Y375384D03*
Y380384D03*
Y385384D03*
Y390384D03*
Y395384D03*
Y400384D03*
Y405384D03*
Y410384D03*
Y415384D03*
Y420384D03*
Y425384D03*
Y430384D03*
Y435384D03*
Y440384D03*
Y445384D03*
Y450384D03*
Y455384D03*
Y460384D03*
Y465384D03*
Y470384D03*
Y475384D03*
Y480384D03*
Y485384D03*
Y530384D03*
Y525384D03*
Y520384D03*
Y515384D03*
Y510384D03*
Y505384D03*
Y490384D03*
Y495384D03*
Y500384D03*
Y535384D03*
Y540384D03*
Y545384D03*
Y550384D03*
Y555384D03*
Y560384D03*
X10266Y565366D03*
X15266D03*
X75364Y5500D03*
X70364D03*
X65364D03*
X60364D03*
X55364D03*
X50364D03*
X45364D03*
X40364D03*
X35364D03*
X30364D03*
X25364D03*
X20364D03*
X20266Y565366D03*
X25266D03*
X30266D03*
X35266D03*
X40266D03*
X45266D03*
X50266D03*
X55266D03*
X60266D03*
X65266D03*
X70266D03*
X75266D03*
X95364Y5500D03*
X90364D03*
X85364D03*
X80364D03*
X80266Y565366D03*
X85266D03*
X90266D03*
X95266D03*
X100266D03*
X105266D03*
X110266D03*
X115266D03*
X120266D03*
X125266D03*
X130266D03*
X135266D03*
X200364Y5500D03*
X195364D03*
X190364D03*
X185364D03*
X180364D03*
X175364D03*
X170364D03*
X177850Y324800D03*
X174995Y353588D03*
Y358388D03*
X165195D03*
X169995D03*
Y353588D03*
X200266Y565366D03*
X195266D03*
X190266D03*
X185266D03*
X180266D03*
X175266D03*
X140266D03*
X145266D03*
X150266D03*
X155266D03*
X160266D03*
X165266D03*
X170266D03*
X260364Y5500D03*
X255364D03*
X250364D03*
X245364D03*
X240364D03*
X235364D03*
X230364D03*
X225364D03*
X220364D03*
X215364D03*
X210364D03*
X205364D03*
X249204Y244103D03*
X212589Y494694D03*
X220589D03*
X216589Y489694D03*
X208589D03*
X224589D03*
X205266Y565366D03*
X210266D03*
X215266D03*
X220266D03*
X225266D03*
X230266D03*
X235266D03*
X240266D03*
X245266D03*
X250266D03*
X255266D03*
X260266D03*
X325364Y5500D03*
X320364D03*
X315364D03*
X310364D03*
X305364D03*
X300364D03*
X295364D03*
X290364D03*
X285364D03*
X280364D03*
X275364D03*
X270364D03*
X265364D03*
X265266Y565366D03*
X270266D03*
X275266D03*
X280266D03*
X285266D03*
X290266D03*
X295266D03*
X300266D03*
X305266D03*
X310266D03*
X315266D03*
X320266D03*
X325266D03*
X330364Y5500D03*
X350586Y495815D03*
X355523Y495025D03*
X360461Y494236D03*
X365398Y493446D03*
X370335Y492656D03*
X375272Y491866D03*
X380210Y491077D03*
X385169Y490563D03*
X329156Y545492D03*
Y540492D03*
Y535492D03*
Y530492D03*
Y525492D03*
Y520492D03*
Y515492D03*
Y560492D03*
Y555492D03*
Y550492D03*
X405169Y490563D03*
X410169D03*
X415169D03*
X420169D03*
X425169D03*
X430169D03*
X435169D03*
X440169D03*
X445146Y490850D03*
X450083Y491640D03*
X390169Y490563D03*
X395169D03*
X400169D03*
X469832Y494799D03*
X474769Y495589D03*
X455020Y492430D03*
X459958Y493219D03*
X464895Y494009D03*
X497636Y515532D03*
Y520532D03*
Y525532D03*
Y530532D03*
Y535532D03*
Y540532D03*
Y545532D03*
Y550532D03*
Y555532D03*
Y560532D03*
X502550Y565366D03*
X507550D03*
X512550D03*
X570234Y298026D03*
X572634Y293526D03*
X529500Y471500D03*
X517550Y565366D03*
X522550D03*
X527550D03*
X532550D03*
X537550D03*
X542550D03*
X547550D03*
X552550D03*
X557550D03*
X562550D03*
X567550D03*
X572550D03*
X591446Y6545D03*
X596446D03*
X601446D03*
X606446D03*
X611446D03*
X616446D03*
X621446D03*
X636446D03*
X631446D03*
X626446D03*
X576797Y113877D03*
X582554Y116361D03*
X575134Y298026D03*
X577534Y293526D03*
X580034Y298026D03*
X632150Y389100D03*
X605534Y480027D03*
X577550Y565366D03*
X582550D03*
X587550D03*
X592550D03*
X597550D03*
X602550D03*
X607550D03*
X612550D03*
X617550D03*
X622550D03*
X627550D03*
X632550D03*
X641446Y6545D03*
X646446D03*
X651446D03*
X696446D03*
X691446D03*
X661446D03*
X656446D03*
X686446D03*
X681446D03*
X676446D03*
X671446D03*
X666446D03*
X675136Y268500D03*
X637705Y298765D03*
X642705D03*
X637705Y303765D03*
X642705D03*
X660100Y307500D03*
X637550Y389050D03*
X688500Y484400D03*
Y488600D03*
X637550Y565366D03*
X642550D03*
X647550D03*
X652550D03*
X657550D03*
X662550D03*
X667550D03*
X672550D03*
X677550D03*
X682550D03*
X687550D03*
X692550D03*
X697550D03*
X701446Y6545D03*
X702550Y565366D03*
X707550D03*
X712550D03*
X717550D03*
X722550D03*
X727550D03*
X732550D03*
X737550D03*
X742550D03*
X747550D03*
X752550D03*
X757550D03*
X821272Y49340D03*
Y44340D03*
Y39340D03*
Y34340D03*
Y29340D03*
Y24340D03*
Y19340D03*
Y14340D03*
Y9340D03*
X815364Y5500D03*
X810364D03*
X805364D03*
X800364D03*
X795364D03*
X790364D03*
X785364D03*
X780364D03*
X775364D03*
X770364D03*
X765364D03*
X821272Y114340D03*
Y109340D03*
Y104340D03*
Y99340D03*
Y94340D03*
Y89340D03*
Y84340D03*
Y79340D03*
Y74340D03*
Y69340D03*
Y64340D03*
Y59340D03*
Y54340D03*
Y174340D03*
Y169340D03*
Y164340D03*
Y159340D03*
Y154340D03*
Y149340D03*
Y144340D03*
Y139340D03*
Y134340D03*
Y129340D03*
Y124340D03*
Y119340D03*
Y234340D03*
Y229340D03*
Y224340D03*
Y219340D03*
Y214340D03*
Y209340D03*
Y204340D03*
Y199340D03*
Y194340D03*
Y189340D03*
Y184340D03*
Y179340D03*
X771083Y211784D03*
X821272Y299340D03*
Y294340D03*
Y289340D03*
Y284340D03*
Y279340D03*
Y274340D03*
Y269340D03*
Y264340D03*
Y259340D03*
Y254340D03*
Y249340D03*
Y244340D03*
Y239340D03*
Y359340D03*
Y354340D03*
Y349340D03*
Y344340D03*
Y339340D03*
Y334340D03*
Y329340D03*
Y324340D03*
Y319340D03*
Y314340D03*
Y309340D03*
Y304340D03*
Y424340D03*
Y419340D03*
Y414340D03*
Y409340D03*
Y404340D03*
Y399340D03*
Y394340D03*
Y389340D03*
Y384340D03*
Y379340D03*
Y374340D03*
Y369340D03*
Y364340D03*
Y484340D03*
Y479340D03*
Y474340D03*
Y469340D03*
Y464340D03*
Y459340D03*
Y454340D03*
Y449340D03*
Y444340D03*
Y439340D03*
Y434340D03*
Y429340D03*
Y504340D03*
Y509340D03*
Y514340D03*
Y519340D03*
Y524340D03*
Y529340D03*
Y549340D03*
Y544340D03*
Y539340D03*
Y534340D03*
Y499340D03*
Y494340D03*
Y489340D03*
X762550Y565366D03*
X767550D03*
X772550D03*
X777550D03*
X782550D03*
X787550D03*
X792550D03*
X797550D03*
X802550D03*
X807550D03*
X812550D03*
X817550D03*
X821272Y559340D03*
Y554340D03*
G54D11*
G01X-34018Y-300855D02*
G02I-12000J0D01*
G01X-39168D02*
G02I-6850J0D01*
G01X-30018D02*
X-62018D01*
G01X-30018Y-316855D02*
Y-396855D01*
G01D02*
X1320682D01*
G01X-30018Y-352355D02*
X1320682D01*
G01X-46018Y-316855D02*
Y-284855D01*
G01X-30018Y-316855D02*
X1320682D01*
G01X220228Y63651D02*
Y61520D01*
X234421Y47327D01*
X316463D01*
X325186Y56050D01*
X336381D01*
G01X503800Y382700D02*
X506713Y385613D01*
X560275D01*
X570815Y375073D01*
X587601D01*
X598336Y364338D01*
Y333164D01*
X611000Y320500D01*
X627437D01*
X631800Y316137D01*
G01X533182Y-316855D02*
Y-396855D01*
G01X623063Y357337D02*
X614759Y349033D01*
X602649D01*
G01X577300Y460300D02*
X583256Y466256D01*
Y468391D01*
X594892Y480027D01*
X605534D01*
G01X670682Y-316855D02*
Y-396855D01*
G01X670078Y151181D02*
X669832D01*
X667162Y153851D01*
Y160640D01*
X663496Y164306D01*
X663005D01*
X657452Y169859D01*
Y187923D01*
X655080Y190295D01*
Y196270D01*
X672625Y213815D01*
X674023D01*
G01X670078Y157480D02*
Y163468D01*
X666941Y166605D01*
Y184763D01*
X673077Y190899D01*
Y207340D01*
X674172Y208435D01*
Y210095D01*
G01X679400Y213300D02*
X682441Y210259D01*
Y198414D01*
X685465Y195390D01*
X692255D01*
X694526Y193119D01*
Y178532D01*
X692382Y176388D01*
X679291D01*
X675771Y172868D01*
Y150574D01*
X673228Y148031D01*
G01X660100Y307500D02*
Y300840D01*
X669450Y291490D01*
Y284900D01*
G01X768700Y129800D02*
X767150Y131350D01*
X762681D01*
X748831Y145200D01*
X742500D01*
X737269Y150431D01*
X728926D01*
X726021Y147526D01*
Y140737D01*
X724615Y139331D01*
X716327D01*
X714173Y141485D01*
Y141732D01*
G01X765764Y326844D02*
Y307264D01*
X756111Y297611D01*
X754227D01*
G01X785682Y-316855D02*
Y-396855D01*
G01X953182Y-316855D02*
Y-396855D01*
G01X1123182Y-316855D02*
Y-396855D01*
G01X1320682Y-316855D02*
Y-396855D01*
G01X1348682Y-300855D02*
G02I-12000J0D01*
G01X1343532D02*
G02I-6850J0D01*
G01X1336682Y-316855D02*
Y-284855D01*
G01X1352682Y-300855D02*
X1320682D01*
X23100Y283200D03*
X22750Y275450D03*
X23500Y296700D03*
X68300Y292200D03*
X28000Y326500D03*
X24000Y301750D03*
X23400Y309500D03*
X67800Y318000D03*
X67700Y321500D03*
X53500Y403150D03*
X49700Y402000D03*
X50700Y378233D03*
X54800Y373600D03*
X29900Y378252D03*
X38200Y373800D03*
X34100D03*
X73100Y378700D03*
X60400Y373600D03*
X77200Y374000D03*
X65375Y392835D03*
X102395Y373793D03*
X93695Y378426D03*
X81300Y374000D03*
X98295Y373793D03*
X155991Y110061D03*
X152800Y113400D03*
X145585Y132451D03*
X162522Y331774D03*
X241750Y98250D03*
X238867Y63650D03*
X234693Y57400D03*
X220228Y63651D03*
X262800Y277835D03*
X242400Y289700D03*
X242402Y286300D03*
X225500Y278900D03*
X222320Y277658D03*
X207500Y278400D03*
X204997Y280702D03*
X212198Y328316D03*
X208648Y328452D03*
X253245Y329698D03*
X253154Y326227D03*
X241556Y340111D03*
X237483Y339988D03*
X230000Y336500D03*
X233400Y336600D03*
X230400Y348000D03*
X281700Y52285D03*
X285500D03*
X308591Y68928D03*
X304591D03*
X308591Y73074D03*
X300311Y60800D03*
X300385Y108227D03*
X311182Y62800D03*
X272937Y90362D03*
X266895Y100227D03*
X306280Y82574D03*
X301280D03*
X304591Y73074D03*
X279385Y100227D03*
X292030Y90574D03*
X296280Y82574D03*
X266406Y277835D03*
X306292Y252825D03*
X302262Y262642D03*
X299635Y288650D03*
X292225Y288267D03*
X297021Y346579D03*
X287350Y351200D03*
X319550Y347169D03*
X305147Y354706D03*
X316050Y342200D03*
X287350Y357700D03*
X322500Y353700D03*
X301500Y337500D03*
X320650Y336456D03*
X306060Y337640D03*
X310200Y337600D03*
X325500Y325400D03*
X314241Y308459D03*
X314300Y311900D03*
X308180Y305200D03*
X305628Y320511D03*
X301628D03*
X325500Y321400D03*
X314400Y327851D03*
X314045Y302900D03*
X314500Y324251D03*
X319100Y330600D03*
X305628Y324511D03*
X324100Y307814D03*
X281150Y332000D03*
X308398Y386479D03*
X304205Y382450D03*
X304398Y386479D03*
X292800Y363800D03*
X300019Y379524D03*
X296079D03*
X325200Y365100D03*
X312398Y386479D03*
X335722Y94574D03*
X329722D03*
X374616Y172378D03*
X370061Y172433D03*
X355500Y144500D03*
X342000Y141600D03*
X374915Y176442D03*
X359969Y124510D03*
X349911Y136954D03*
X341757Y211056D03*
X335701Y223995D03*
X357546Y230354D03*
X360710Y231897D03*
X376306Y182715D03*
X371124Y178760D03*
X372517Y182362D03*
X328134Y252720D03*
X332000Y266336D03*
X376633Y261543D03*
X340280Y253765D03*
X337500Y266050D03*
X358096Y262268D03*
X341998Y256700D03*
X368610Y257299D03*
X376633Y256851D03*
X335400Y337400D03*
X345700Y349773D03*
X337600Y349600D03*
X339000Y344700D03*
X330000Y345800D03*
X327400Y342600D03*
X386159Y337080D03*
X331026Y303354D03*
X328100Y331300D03*
X329364Y316949D03*
X344000Y388500D03*
X340375Y365944D03*
X331765Y386535D03*
X367450Y409955D03*
X367350Y406455D03*
X337592Y405027D03*
X448300Y337500D03*
X444100Y341000D03*
X444200Y337600D03*
X444100Y345000D03*
X440300Y337500D03*
X490877Y185047D03*
Y180547D03*
X510427Y184931D03*
Y180431D03*
X500302Y184989D03*
Y180489D03*
X452300Y337500D03*
X468300D03*
X456550D03*
X464300D03*
X460800Y337562D03*
X460300Y333500D03*
X502138Y348500D03*
X506262D03*
X510138D03*
X503800Y382700D03*
X510200Y363209D03*
X506200D03*
X494400Y363800D03*
X499100Y363409D03*
X510700Y367309D03*
X506700D03*
X474200Y367500D03*
X457599Y419642D03*
X496300Y378935D03*
X489500Y371200D03*
X553500Y231900D03*
X549000D03*
X520552Y184873D03*
Y180373D03*
X550717Y255796D03*
X546217D03*
X550975Y248209D03*
X546475D03*
X551865Y240638D03*
X547365D03*
X556800Y339300D03*
X536200Y348300D03*
X540200D03*
X550100D03*
X546100D03*
X632416Y31609D03*
X627603Y43523D03*
X626786Y31227D03*
X627500Y64500D03*
X629500Y61500D03*
X589706Y174031D03*
X586081Y158407D03*
X585145Y162809D03*
X595402Y149579D03*
X594466Y153981D03*
X588070Y138220D03*
X587134Y142622D03*
X576868Y127381D03*
X575932Y131783D03*
X618400Y173443D03*
X589135Y214107D03*
X588199Y218509D03*
X585010Y198483D03*
X584074Y202885D03*
X580885Y182859D03*
X579949Y187261D03*
X588770Y178433D03*
X627455Y185364D03*
X631800Y316137D03*
X590350Y323011D03*
X629250Y310491D03*
Y306491D03*
X626405Y314991D03*
X623063Y357337D03*
X602649Y349033D03*
X594400Y357000D03*
Y353000D03*
X589394Y384572D03*
X589391Y378202D03*
X627140Y381353D03*
X631140D03*
X594200Y395200D03*
X604832Y395220D03*
X577300Y460300D03*
X647216Y31601D03*
X667900Y40800D03*
X643816Y31573D03*
X640144Y40969D03*
X664301Y49998D03*
X668100Y56100D03*
X641003Y68809D03*
X670078Y151181D03*
Y157480D03*
X673228Y148031D03*
X692126Y125984D03*
X685827Y116535D03*
X670079Y125985D03*
X682678D03*
X676378D03*
X688977D03*
X676378Y119686D03*
X666929Y119685D03*
X663780Y125985D03*
X657479Y116536D03*
X654330Y116535D03*
Y119685D03*
Y122834D03*
X657480Y125984D03*
X654331D03*
X654330Y129134D03*
Y132283D03*
Y135433D03*
X651181D03*
X654330Y138582D03*
Y141732D03*
Y144882D03*
X651181D03*
X654330Y148031D03*
Y151181D03*
X674023Y213815D03*
X674172Y210095D03*
X679400Y213300D03*
X679527Y198424D03*
X668600Y242800D03*
X669450Y284900D03*
X695600Y244354D03*
X695375Y260875D03*
X658601Y401800D03*
X673900Y418880D03*
X744833Y78995D03*
X750773Y74636D03*
X747919Y76667D03*
X720744Y92427D03*
X714173Y141732D03*
X738352Y174615D03*
X729920Y176378D03*
Y173229D03*
X736219Y170079D03*
X733070D03*
X750550Y135200D03*
X729921Y160629D03*
Y154330D03*
Y179527D03*
X720471Y198424D03*
X731915Y206310D03*
X738952Y184215D03*
X744052Y193784D03*
X701574Y198424D03*
X711023Y198425D03*
X704724D03*
X717322D03*
X707873Y198424D03*
X723621D03*
X705336Y208437D03*
X711310Y207023D03*
X749620Y273620D03*
X754227Y297611D03*
X755693Y259540D03*
X753560Y273780D03*
X704708Y260647D03*
X743480Y439080D03*
X700855Y426719D03*
X799500Y106000D03*
X781000Y88000D03*
Y84200D03*
X768250Y106300D03*
X768100Y109700D03*
X763560Y59820D03*
X768700Y129800D03*
X793837Y279636D03*
Y275696D03*
X780837Y267826D03*
X784837Y263891D03*
Y259951D03*
X793852Y256011D03*
Y252076D03*
X793837Y271761D03*
Y267826D03*
Y263696D03*
X774657Y255999D03*
X765638Y255635D03*
X774637Y251876D03*
X784837Y271761D03*
Y267826D03*
X793837Y287696D03*
X780837Y271761D03*
X767890Y273380D03*
X765764Y326844D03*
X776497Y338392D03*
X775672Y350204D03*
G54D12*
X388189Y29922D03*
X374016D03*
X359843D03*
X345670D03*
X388189Y24410D03*
X374016D03*
X359843D03*
X345670D03*
X388189Y5906D03*
X374016D03*
X359843D03*
X345670D03*
X381103Y34646D03*
X366929D03*
X352756D03*
X381103Y29134D03*
X366929D03*
X352756D03*
X444882Y29922D03*
X430709D03*
X416536D03*
X402363D03*
X444882Y24410D03*
X430709D03*
X416536D03*
X402363D03*
X444882Y5906D03*
X430709D03*
X416536D03*
X402363D03*
X437796Y34646D03*
X423622D03*
X409449D03*
X395276D03*
X437796Y29134D03*
X423622D03*
X409449D03*
X395276D03*
X501575Y5906D03*
X487402D03*
X473229D03*
X459055D03*
X451969Y34646D03*
Y29134D03*
X572441Y5906D03*
X558268D03*
X544095D03*
X529922D03*
X515748D03*
X586614Y29922D03*
Y24410D03*
Y5906D03*
X758267Y29922D03*
X744094D03*
X715748D03*
X758267Y24410D03*
X744094D03*
X729921D03*
X715748D03*
X758267Y5906D03*
X744094D03*
X729921D03*
X715748D03*
X751181Y34646D03*
Y29134D03*
G54D13*
X401575Y232284D03*
X401727Y228641D03*
X405512Y232284D03*
X413386D03*
X405512Y228347D03*
X448818Y295276D03*
X421260Y259843D03*
X429134Y263781D03*
X440945Y295276D03*
Y299213D03*
Y291339D03*
Y287402D03*
X437008Y295276D03*
X448819Y244095D03*
X440945D03*
X433071D03*
X421259Y240158D03*
X421260Y244095D03*
X417323Y240157D03*
X448819Y307088D03*
X448818Y311024D03*
Y303151D03*
X444882Y314961D03*
Y318898D03*
X433071Y314961D03*
X431102Y331263D03*
X442800Y330300D03*
X446200Y327400D03*
X440945Y303150D03*
Y311024D03*
Y307087D03*
X444881Y322835D03*
X442913Y327204D03*
X440944Y322835D03*
X438976Y327204D03*
X437008Y318898D03*
Y314961D03*
X500000Y208662D03*
X503937D03*
X496063Y212599D03*
X500000D03*
X496063Y216536D03*
X500000D03*
X496063Y220473D03*
X500000D03*
X496063Y224410D03*
X500000D03*
X496063Y228347D03*
X500000D03*
X496063Y232284D03*
X500000D03*
X496063Y236221D03*
X500000D03*
X472442Y287402D03*
X452755D03*
Y291340D03*
Y295277D03*
X464568Y287402D03*
X480316Y287403D03*
X484252Y291340D03*
Y287402D03*
X488189Y295276D03*
X480315Y291339D03*
X476378Y267717D03*
Y275591D03*
Y259843D03*
Y251969D03*
X472441Y244095D03*
X464567D03*
X456693D03*
X460630Y291339D03*
Y307087D03*
X456693D03*
X460630Y311024D03*
X462599Y327204D03*
X456693Y311024D03*
X452755Y303150D03*
X488189D03*
X503937Y311024D03*
X464567Y307088D03*
X492126Y307087D03*
X488189Y322835D03*
G54D14*
G01X155991Y110061D02*
Y118251D01*
X136556Y137686D01*
Y179231D01*
X125300Y190487D01*
Y294552D01*
X162522Y331774D01*
G01X145585Y132451D02*
X138756Y139280D01*
Y181631D01*
X127500Y192887D01*
Y293640D01*
X222140Y388280D01*
X262093D01*
X288463Y414650D01*
X359155D01*
X367350Y406455D01*
G01X367450Y409955D02*
X351155Y426250D01*
X296951D01*
X273993Y403292D01*
X234040D01*
X162522Y331774D01*
G01X359969Y124510D02*
X475990D01*
X536000Y64500D01*
X574760D01*
X582800Y56460D01*
Y29701D01*
X586614Y25887D01*
Y24410D01*
G01X357546Y230354D02*
Y231703D01*
X360304Y234461D01*
X369439D01*
X377353Y226547D01*
X410195D01*
X423060Y239412D01*
Y258043D01*
X421260Y259843D01*
G01X360710Y231897D02*
X367787D01*
X377074Y222610D01*
X425943D01*
X426997Y223664D01*
Y261644D01*
X429134Y263781D01*
G01X744833Y78995D02*
X729600D01*
X724005Y73400D01*
X685400D01*
X668100Y56100D01*
G01X743480Y439080D02*
X755233Y427327D01*
Y306551D01*
X749620Y300938D01*
Y273620D01*
G54D15*
G01X177850Y324800D02*
Y274850D01*
X205500Y247200D01*
X246107D01*
X249204Y244103D01*
G01X590350Y323011D02*
Y296182D01*
X584800Y290632D01*
Y233575D01*
X558774Y207549D01*
Y122993D01*
X567617Y114150D01*
X576524D01*
X576797Y113877D01*
G01X626405Y314991D02*
X619200D01*
X590000Y285791D01*
Y231421D01*
X563974Y205395D01*
Y125147D01*
X569771Y119350D01*
X579565D01*
X582554Y116361D01*
G01X799500Y106000D02*
Y172131D01*
X797012Y174619D01*
Y232736D01*
X803452Y239176D01*
Y260448D01*
X801557Y262343D01*
Y275824D01*
X797881Y279500D01*
Y440419D01*
X743932Y494368D01*
X565364D01*
X542496Y471500D01*
X529500D01*
G01X771083Y211784D02*
X765069Y205770D01*
Y188923D01*
X774643Y179349D01*
Y155998D01*
X790100Y140541D01*
Y97100D01*
X781000Y88000D01*
G01Y84200D02*
Y88000D01*
G54D16*
G01X490877Y185047D02*
Y183924D01*
G03X491032Y183552I527J1D01*
G01X491069Y183515D01*
G03X491352Y183397I284J282D01*
G01X492580D01*
G03X493724Y184541I0J1144D01*
G01Y188446D01*
X501368Y196090D01*
Y199667D01*
G01X490877Y180547D02*
Y181669D01*
G02X491032Y182043I529J0D01*
G02X491404Y182197I372J-372D01*
G01X492580D01*
G03X494924Y184541I0J2344D01*
G01Y187948D01*
X499810Y192834D01*
X500871D01*
X501719Y193683D01*
Y194743D01*
X502568Y195592D01*
Y199667D01*
G01X505315Y199175D02*
Y184656D01*
G02X503998Y183339I-1317J0D01*
G01X500777D01*
G02X500494Y183457I1J400D01*
G01X500457Y183494D01*
G02X500302Y183866I372J373D01*
G01Y184989D01*
G01X506515Y199175D02*
Y190464D01*
X507265Y189714D01*
Y188514D01*
X506515Y187764D01*
Y184656D01*
G02X503998Y182139I-2517J0D01*
G01X500829D01*
G03X500457Y181985I0J-526D01*
G03X500302Y181611I374J-374D01*
G01Y180489D01*
G01X510427Y184931D02*
Y183808D01*
G03X510582Y183436I527J1D01*
G01X510619Y183399D01*
G03X510902Y183281I284J282D01*
G01X512308D01*
G03X513158Y184131I0J850D01*
G01Y189884D01*
X509250Y193792D01*
Y199711D01*
G01X510427Y180431D02*
Y181553D01*
G02X510582Y181927I529J0D01*
G02X510954Y182081I372J-372D01*
G01X512308D01*
G03X514358Y184131I0J2050D01*
G01Y186260D01*
X515108Y187010D01*
Y188210D01*
X514358Y188960D01*
Y190382D01*
X510450Y194290D01*
Y199711D01*
G01X520552Y184873D02*
Y183750D01*
G03X520707Y183378I527J1D01*
G01X520744Y183341D01*
G03X521027Y183223I284J282D01*
G01X523172D01*
G03X524004Y184055I0J832D01*
G01Y190469D01*
X513600Y200873D01*
Y211838D01*
G01X520552Y180373D02*
Y181495D01*
G02X520707Y181869I529J0D01*
G02X521079Y182023I372J-372D01*
G01X523172D01*
G03X525204Y184055I0J2032D01*
G01Y190967D01*
X524355Y191816D01*
Y192876D01*
X523507Y193725D01*
X522446D01*
X514800Y201371D01*
Y211838D01*
G01X509050Y221836D02*
X529836D01*
X536250Y228250D01*
X549798D01*
G03X551850Y230302I0J2052D01*
G01Y231239D01*
G02X552044Y231707I661J0D01*
G02X552510Y231900I466J-466D01*
G01X553500D01*
G01X509050Y223036D02*
X529338D01*
X535752Y229450D01*
X537736D01*
X538486Y230200D01*
X539686D01*
X540436Y229450D01*
X549798D01*
G03X550650Y230302I0J852D01*
G01Y231175D01*
G03X550439Y231687I-727J0D01*
G01X550438Y231688D01*
G03X549924Y231900I-513J-514D01*
G01X549000D01*
G01X518488Y228103D02*
X527519D01*
X536404Y236988D01*
X548163D01*
G03X550215Y239040I0J2052D01*
G01Y239977D01*
G02X550409Y240445I661J0D01*
G02X550875Y240638I466J-466D01*
G01X551865D01*
G01X518488Y229303D02*
X527021D01*
X533148Y235430D01*
Y236491D01*
X533997Y237339D01*
X535057D01*
X535906Y238188D01*
X548163D01*
G03X549015Y239040I0J852D01*
G01Y239913D01*
G03X548804Y240425I-727J0D01*
G01X548803Y240426D01*
G03X548289Y240638I-513J-514D01*
G01X547365D01*
G01X518472Y231299D02*
X522401D01*
X535661Y244559D01*
X547273D01*
G03X549325Y246611I0J2052D01*
G01Y247548D01*
G02X549519Y248016I661J0D01*
G02X549985Y248209I466J-466D01*
G01X550975D01*
G01X518472Y232499D02*
X521903D01*
X532405Y243001D01*
Y244062D01*
X533254Y244910D01*
X534314D01*
X535163Y245759D01*
X547273D01*
G03X548125Y246611I0J852D01*
G01Y247484D01*
G03X547914Y247996I-727J0D01*
G01X547913Y247997D01*
G03X547399Y248209I-513J-514D01*
G01X546475D01*
G01X510483Y233653D02*
X512436D01*
X514957Y236174D01*
X519838D01*
X535810Y252146D01*
X547015D01*
G03X549067Y254198I0J2052D01*
G01Y255135D01*
G02X549261Y255603I661J0D01*
G02X549727Y255796I466J-466D01*
G01X550717D01*
G01X510483Y234853D02*
X511938D01*
X514459Y237374D01*
X519340D01*
X532554Y250588D01*
Y251649D01*
X533403Y252497D01*
X534463D01*
X535312Y253346D01*
X547015D01*
G03X547867Y254198I0J852D01*
G01Y255071D01*
G03X547656Y255583I-727J0D01*
G01X547655Y255584D01*
G03X547141Y255796I-513J-514D01*
G01X546217D01*
G01X650971Y114735D02*
X642939D01*
X624167Y118725D01*
X612793Y126112D01*
X587878Y131408D01*
X586521Y131123D01*
X579088Y129540D01*
X577040Y129105D01*
G03X576709Y128877I110J-515D01*
G03X576635Y128479I443J-288D01*
G01X576868Y127381D01*
G01X575932Y131783D02*
X576165Y130684D01*
G03X576394Y130353I515J112D01*
G01X576438Y130324D01*
G03X576740Y130268I218J335D01*
G01X578838Y130714D01*
X586272Y132297D01*
X587878Y132635D01*
X595034Y131114D01*
X595924Y131692D01*
X597097Y131442D01*
X597675Y130553D01*
X598849Y130303D01*
X599738Y130881D01*
X600912Y130631D01*
X601490Y129742D01*
X602664Y129492D01*
X603553Y130070D01*
X604727Y129820D01*
X605305Y128931D01*
X613260Y127240D01*
X624634Y119853D01*
X631295Y118437D01*
X632185Y119015D01*
X633359Y118765D01*
X633936Y117876D01*
X635110Y117626D01*
X636000Y118204D01*
X637174Y117954D01*
X637751Y117065D01*
X643066Y115935D01*
X650971D01*
G01X654330Y119685D02*
Y120284D01*
G03X653984Y120682I-346J49D01*
G01X653092D01*
X652110Y119700D01*
X644847D01*
X625185Y123879D01*
X613776Y131290D01*
X602738Y138459D01*
X592276Y140682D01*
X588225Y139940D01*
G03X587911Y139716I127J-511D01*
G03X587837Y139318I443J-288D01*
G01X588070Y138220D01*
G01X654330Y122834D02*
Y122365D01*
G02X654188Y122023I-483J0D01*
G02X653848Y121882I-340J339D01*
G01X652594D01*
X651612Y120900D01*
X644974D01*
X625652Y125007D01*
X620041Y128653D01*
X603205Y139587D01*
X592431Y141877D01*
Y141876D01*
X592429D01*
X592430Y141877D01*
X592293Y141906D01*
X587982Y141116D01*
G03X587930Y141104I362J-1688D01*
G01Y141105D01*
X587640Y141163D01*
X587596Y141192D01*
G02X587367Y141523I286J443D01*
G01X587134Y142622D01*
G01X650522Y124774D02*
X646028D01*
X643908Y126894D01*
X632999D01*
X609145Y142383D01*
X608428Y142849D01*
X603672Y150173D01*
X601970Y151277D01*
X598921Y152014D01*
X595574Y151303D01*
G03X595243Y151075I110J-515D01*
G03X595169Y150677I443J-288D01*
G01X595402Y149579D01*
G01X650522Y125974D02*
X646526D01*
X644406Y128094D01*
X633355D01*
X632349Y128748D01*
X632128Y129785D01*
X631122Y130439D01*
X630084Y130218D01*
X629078Y130872D01*
X628857Y131909D01*
X627851Y132563D01*
X626813Y132342D01*
X625807Y132996D01*
X625586Y134033D01*
X624580Y134687D01*
X623542Y134466D01*
X619109Y137345D01*
X618888Y138382D01*
X617882Y139036D01*
X616844Y138815D01*
X615838Y139469D01*
X615617Y140506D01*
X614611Y141160D01*
X613573Y140939D01*
X612567Y141593D01*
X612346Y142630D01*
X611340Y143284D01*
X610302Y143063D01*
X609296Y143717D01*
X604540Y151041D01*
X602452Y152396D01*
X598938Y153245D01*
X595324Y152477D01*
G03X595274Y152466I346J-1692D01*
G02X594972Y152522I-84J391D01*
G01X594928Y152551D01*
G02X594699Y152882I286J443D01*
G01X594466Y153981D01*
G01X644867Y130605D02*
X636026D01*
X634809Y130863D01*
X610645Y146555D01*
X605457Y154544D01*
X600878Y157516D01*
X599841Y157296D01*
X598834Y157949D01*
X598613Y158987D01*
X596598Y160295D01*
X592503Y161457D01*
X586253Y160131D01*
G03X585922Y159903I110J-515D01*
G03X585848Y159505I443J-288D01*
G01X586081Y158407D01*
G01X585145Y162809D02*
X585378Y161710D01*
G03X585607Y161379I515J112D01*
G01X585651Y161350D01*
G03X585953Y161294I218J335D01*
G02X586003Y161305I396J-1681D01*
G01X592545Y162693D01*
X597100Y161400D01*
X606325Y155412D01*
X611513Y147423D01*
X635276Y131991D01*
X636152Y131805D01*
X644867D01*
G01X644428Y134167D02*
X641958D01*
X633558Y135950D01*
X614890Y148072D01*
X614173Y148538D01*
X597183Y174710D01*
X596174Y175364D01*
X593159Y176452D01*
X589878Y175755D01*
G03X589547Y175527I110J-515D01*
G03X589473Y175129I443J-288D01*
G01X589706Y174031D01*
G01X644428Y135367D02*
X642085D01*
X642084Y135368D01*
X640176Y135773D01*
X639598Y136662D01*
X638425Y136911D01*
X637535Y136333D01*
X634025Y137078D01*
X628125Y140910D01*
X627904Y141947D01*
X626898Y142601D01*
X625860Y142380D01*
X624854Y143034D01*
X624633Y144071D01*
X623627Y144725D01*
X622589Y144504D01*
X621583Y145158D01*
X621362Y146196D01*
X620356Y146849D01*
X619318Y146628D01*
X618312Y147282D01*
X618091Y148319D01*
X617085Y148973D01*
X616047Y148752D01*
X615041Y149406D01*
X598051Y175578D01*
X596712Y176447D01*
X593244Y177697D01*
Y177698D01*
X589628Y176929D01*
G03X589578Y176918I346J-1692D01*
G02X589276Y176974I-84J391D01*
G01X589232Y177003D01*
G02X589003Y177334I286J443D01*
G01X588770Y178433D01*
G01X580885Y182859D02*
X580652Y183957D01*
G02X580726Y184355I517J110D01*
G02X581057Y184583I441J-287D01*
G01X587708Y185998D01*
X593577Y184610D01*
X596418Y182766D01*
X605831Y168267D01*
X611881Y158948D01*
X615522Y153341D01*
X633075Y141935D01*
X633295Y140897D01*
X634343Y140216D01*
X635381Y140436D01*
X636429Y139755D01*
X641948Y138583D01*
X652084D01*
X653081Y139580D01*
X653984D01*
G02X654330Y139182I0J-349D01*
G01Y138582D01*
G01X579949Y187261D02*
X580182Y186162D01*
G03X580411Y185831I515J112D01*
G01X580455Y185802D01*
G03X580757Y185746I218J335D01*
G02X580807Y185757I396J-1681D01*
G01X587722Y187228D01*
X594056Y185730D01*
X597286Y183634D01*
X616390Y154209D01*
X636897Y140883D01*
X642075Y139783D01*
X651586D01*
X652583Y140780D01*
X653848D01*
G03X654188Y140921I0J480D01*
G03X654330Y141263I-341J342D01*
G01Y141732D01*
G01X649487Y143682D02*
X645895D01*
X638166Y145322D01*
X615926Y159764D01*
X596733Y189315D01*
X595409Y195548D01*
X592887Y199430D01*
X585863Y200351D01*
X585169Y200204D01*
G03X584851Y199979I123J-512D01*
G03X584777Y199581I443J-288D01*
G01X585010Y198483D01*
G01X584074Y202885D02*
X584307Y201786D01*
G03X584536Y201455I515J112D01*
G01X584580Y201426D01*
G03X584882Y201370I218J335D01*
G01X585815Y201568D01*
X593592Y200548D01*
X596537Y196015D01*
X597861Y189782D01*
X610381Y170506D01*
X611418Y170286D01*
X612072Y169279D01*
X611851Y168242D01*
X612505Y167236D01*
X613542Y167015D01*
X614196Y166009D01*
X613976Y164971D01*
X614629Y163965D01*
X615667Y163744D01*
X616320Y162738D01*
X616100Y161701D01*
X616794Y160632D01*
X632091Y150698D01*
X633129Y150919D01*
X634135Y150265D01*
X634356Y149228D01*
X635362Y148574D01*
X636400Y148795D01*
X637406Y148141D01*
X637627Y147104D01*
X638633Y146450D01*
X646021Y144882D01*
X651181D01*
G01X654330Y148031D02*
Y148631D01*
G03X653984Y149029I-346J49D01*
G01X653076D01*
X652211Y148164D01*
X646140D01*
X643784Y148665D01*
X641335Y149185D01*
X619684Y163242D01*
X604301Y186942D01*
X600633Y204186D01*
X599743Y204764D01*
X599493Y205938D01*
X600071Y206827D01*
X599821Y208001D01*
X595949Y213961D01*
X591213Y216235D01*
X589289Y215826D01*
G03X588976Y215603I128J-510D01*
G03X588902Y215205I443J-288D01*
G01X589135Y214107D01*
G01X654330Y151181D02*
Y150712D01*
G02X654188Y150370I-483J0D01*
G02X653848Y150229I-340J339D01*
G01X652578D01*
X651713Y149364D01*
X646267D01*
X645411Y149547D01*
X641802Y150313D01*
X620552Y164110D01*
X605429Y187409D01*
X600949Y208469D01*
X596772Y214897D01*
X591364Y217494D01*
X589007Y216994D01*
G02X588705Y217050I-84J391D01*
G01X588661Y217079D01*
G02X588432Y217410I286J443D01*
G01X588199Y218509D01*
G54D17*
G01X594200Y395200D02*
X590535Y398865D01*
X364099D01*
X356050Y406914D01*
X300013D01*
X282399Y389300D01*
X276668D01*
X263040Y375672D01*
X242643D01*
X194750Y327779D01*
Y278802D01*
X218652Y254900D01*
X248169D01*
X265374Y237695D01*
X270027D01*
X273100Y234622D01*
Y200947D01*
X276885Y197162D01*
Y96216D01*
X293027Y80074D01*
X356682D01*
X378580Y58176D01*
Y37169D01*
X381103Y34646D01*
G01X604832Y395220D02*
X598687Y401365D01*
X365635D01*
X357586Y409414D01*
X297417D01*
X279803Y391800D01*
X270417D01*
X256789Y378172D01*
X241607D01*
X192250Y328815D01*
Y277766D01*
X217617Y252399D01*
X247134D01*
X266567Y232966D01*
X268845D01*
X270409Y231402D01*
Y122404D01*
X274385Y118428D01*
Y95180D01*
X291991Y77574D01*
X355646D01*
X375875Y57345D01*
Y51217D01*
X376576Y50516D01*
Y33652D01*
X381094Y29134D01*
X381103D01*
G01X234693Y57400D02*
X241826Y50267D01*
X314943D01*
X323476Y58800D01*
X338944D01*
X343076Y54668D01*
Y32516D01*
X345670Y29922D01*
G01X336381Y56050D02*
X338865D01*
X341067Y53848D01*
Y29013D01*
X345670Y24410D01*
G01X212198Y328316D02*
Y311802D01*
X217400Y306600D01*
Y278783D01*
X223219Y272964D01*
X252736D01*
X262852Y262848D01*
X270068D01*
X289384Y243532D01*
Y227824D01*
X300657Y216551D01*
Y187463D01*
X308352Y179768D01*
X310021D01*
X314581Y175208D01*
Y132075D01*
X336486Y110170D01*
X373883D01*
X373884Y110171D01*
X379684D01*
X427455Y62400D01*
X427456D01*
X432872Y56984D01*
Y56983D01*
X435161Y54694D01*
Y53038D01*
X435160Y53037D01*
Y44587D01*
X435167Y44553D01*
X435169Y44206D01*
Y38146D01*
X435160Y38100D01*
Y28861D01*
X430709Y24410D01*
G01X208648Y328452D02*
Y312223D01*
X215400Y305471D01*
Y277954D01*
X222390Y270964D01*
X251907D01*
X262023Y260848D01*
X269239D01*
X287384Y242703D01*
Y226995D01*
X298657Y215722D01*
Y183834D01*
X304882Y177609D01*
Y147624D01*
X312581Y139925D01*
Y128488D01*
X320576Y120493D01*
X322086D01*
X325876Y116703D01*
Y114507D01*
X332213Y108170D01*
X374712D01*
X374713Y108171D01*
X378855D01*
X426626Y60400D01*
X426627D01*
X430872Y56155D01*
Y56154D01*
X433160Y53866D01*
Y44388D01*
X433168Y44348D01*
X433169Y44199D01*
Y38340D01*
X433160Y38294D01*
Y32373D01*
X430709Y29922D01*
G01X242400Y289700D02*
X247858D01*
X266710Y270848D01*
X277808D01*
X288628Y260028D01*
X289773D01*
X293629Y256172D01*
Y250603D01*
X302302Y241930D01*
Y233794D01*
X307369Y228727D01*
X309862D01*
X313157Y225432D01*
Y197467D01*
X323940Y186684D01*
Y136973D01*
X333512Y127401D01*
Y125984D01*
X341326Y118170D01*
X370567D01*
X370568Y118171D01*
X384444D01*
X384445Y118170D01*
X385908D01*
X385909Y118171D01*
X387565D01*
X449452Y56284D01*
Y28980D01*
X444882Y24410D01*
G01Y29922D02*
X447452Y32492D01*
Y55455D01*
X386737Y116170D01*
X383616D01*
X383615Y116171D01*
X371397D01*
X371396Y116170D01*
X338973D01*
X325630Y129513D01*
Y132370D01*
X321146Y136854D01*
Y185043D01*
X311157Y195032D01*
Y216632D01*
X310127Y217662D01*
X308137D01*
X300302Y225497D01*
Y241101D01*
X288612Y252791D01*
Y257215D01*
X276979Y268848D01*
X265881D01*
X248429Y286300D01*
X242402D01*
G01X225500Y278900D02*
X227337Y277063D01*
X254837D01*
X265052Y266848D01*
X271726D01*
X293384Y245190D01*
Y229482D01*
X304866Y218000D01*
Y193846D01*
X307787Y190925D01*
X309864D01*
X318924Y181865D01*
Y133390D01*
X338144Y114170D01*
X372225D01*
X372226Y114171D01*
X382786D01*
X442256Y54701D01*
Y33594D01*
X437796Y29134D01*
G01Y34646D02*
X440256Y37106D01*
Y53872D01*
X381958Y112170D01*
X380514D01*
X380513Y112171D01*
X373055D01*
X373054Y112170D01*
X337315D01*
X316924Y132561D01*
Y178465D01*
X310304Y185085D01*
X308158D01*
X302866Y190377D01*
Y217171D01*
X291384Y228653D01*
Y244361D01*
X270897Y264848D01*
X264152D01*
X253972Y275028D01*
X224950D01*
X222320Y277658D01*
G01X423622Y34646D02*
X426082Y37106D01*
Y53873D01*
X424555Y55400D01*
X424554D01*
X376784Y103170D01*
X327441D01*
X320988Y109623D01*
Y110211D01*
X305990Y125209D01*
Y138278D01*
X299882Y144386D01*
Y175537D01*
X290500Y184919D01*
Y199337D01*
X282383Y207454D01*
Y240632D01*
X267167Y255848D01*
X259951D01*
X249837Y265962D01*
X220320D01*
X210399Y275883D01*
Y302899D01*
X203648Y309650D01*
Y329605D01*
X237477Y363434D01*
X262384D01*
X265025Y366075D01*
Y367608D01*
X279317Y381900D01*
X285258D01*
X298196Y394838D01*
Y394839D01*
X299720Y396363D01*
X564730D01*
X564791Y396302D01*
X584736D01*
X594395Y386643D01*
Y384092D01*
X596558Y381929D01*
X597257Y381231D01*
X609716D01*
X609838Y381353D01*
X627140D01*
G01X423622Y29134D02*
X428249Y33761D01*
Y44093D01*
X428247Y44326D01*
X428249Y44337D01*
Y50616D01*
X428582Y50949D01*
Y54909D01*
X425590Y57901D01*
X425589D01*
X377819Y105671D01*
X375749D01*
X375748Y105670D01*
X328477D01*
X324197Y109950D01*
Y112650D01*
X308490Y128357D01*
Y140277D01*
X302382Y146385D01*
Y176573D01*
X293001Y185954D01*
Y200372D01*
X284884Y208489D01*
Y241667D01*
X268203Y258348D01*
X260987D01*
X250872Y268463D01*
X221355D01*
X212899Y276919D01*
Y303936D01*
X206148Y310687D01*
Y328569D01*
X238513Y360934D01*
X266051D01*
X270800Y365683D01*
Y369847D01*
X280353Y379400D01*
X286294D01*
X300757Y393863D01*
X563694D01*
X563755Y393802D01*
X583700D01*
X591895Y385607D01*
Y383055D01*
X596220Y378731D01*
X628518D01*
X631140Y381353D01*
G01X253154Y326227D02*
X255500Y323881D01*
Y304743D01*
X290795Y269448D01*
X298285D01*
X309705Y258028D01*
Y256050D01*
X325157Y240598D01*
Y203557D01*
X335940Y192774D01*
Y147660D01*
X342000Y141600D01*
G01X416536Y24410D02*
X421043Y28917D01*
Y49930D01*
X370303Y100670D01*
X323569D01*
X316622Y107617D01*
Y110526D01*
X303490Y123658D01*
Y136912D01*
X284411Y155991D01*
Y201889D01*
X279881Y206419D01*
Y239598D01*
X266131Y253348D01*
X258915D01*
X248801Y263462D01*
X219284D01*
X207500Y275246D01*
Y278400D01*
G01X416536Y29922D02*
X419043Y32429D01*
Y49101D01*
X369474Y98670D01*
X321777D01*
X301490Y118957D01*
Y135743D01*
X282256Y154977D01*
Y201073D01*
X277881Y205448D01*
Y238769D01*
X269422Y247228D01*
X262206D01*
X248035Y261399D01*
X218518D01*
X204997Y274920D01*
Y280702D01*
G01X279385Y100227D02*
Y198285D01*
X275600Y202070D01*
Y237346D01*
X270447Y242499D01*
X264106D01*
X249205Y257400D01*
X219688D01*
X201148Y275940D01*
Y330641D01*
X243679Y373172D01*
X264076D01*
X277704Y386800D01*
X283435D01*
X296231Y399596D01*
X332161D01*
X337592Y405027D01*
G01X586614Y29922D02*
X589379Y32687D01*
Y53063D01*
X575556Y66886D01*
X536982D01*
X476568Y127300D01*
X347813D01*
X329940Y145173D01*
Y190286D01*
X319157Y201069D01*
Y236514D01*
X302264Y253407D01*
Y257995D01*
X294231Y266028D01*
X291344D01*
X244627Y312745D01*
X236438D01*
X227633Y321550D01*
Y345233D01*
X230400Y348000D01*
G01X632416Y31609D02*
X630492D01*
X628260Y29377D01*
X625807D01*
X582298Y72886D01*
X539798D01*
X477731Y134953D01*
X349135D01*
X345518Y138570D01*
Y144722D01*
X337940Y152300D01*
Y193603D01*
X327157Y204386D01*
Y241427D01*
X311775Y256809D01*
Y258787D01*
X299002Y271560D01*
X291513D01*
X257500Y305572D01*
Y325443D01*
X253245Y329698D01*
G01X758267Y24410D02*
X767560Y33703D01*
Y66124D01*
X748439Y85245D01*
X726227D01*
X721271Y80289D01*
X618000D01*
X598369Y99920D01*
X550434D01*
X484855Y165499D01*
X431030D01*
X405029Y191500D01*
X393900D01*
X370810Y214590D01*
X364469D01*
X349554Y229505D01*
Y236004D01*
X334279Y251279D01*
Y254850D01*
X320749Y268380D01*
X316407D01*
X303227Y281560D01*
X296160D01*
X288850Y288870D01*
Y306347D01*
X285763Y309434D01*
Y334883D01*
X280535Y340111D01*
X241556D01*
G01X758267Y29922D02*
X765560Y37215D01*
Y65295D01*
X747610Y83245D01*
X727056D01*
X722100Y78289D01*
X617171D01*
X597540Y97920D01*
X549605D01*
X484026Y163499D01*
X430201D01*
X404700Y189000D01*
X392830D01*
X369240Y212590D01*
X363640D01*
X347140Y229090D01*
Y235589D01*
X332279Y250450D01*
Y254021D01*
X320198Y266102D01*
X315856D01*
X302398Y279560D01*
X295331D01*
X286850Y288041D01*
Y305518D01*
X283763Y308605D01*
Y334054D01*
X279893Y337924D01*
X239547D01*
X237483Y339988D01*
G01X715748Y24410D02*
X711253Y28905D01*
Y53740D01*
X709593Y55400D01*
X704825D01*
X679585Y30160D01*
X651475D01*
X647620Y34015D01*
X627130D01*
X584259Y76886D01*
X541456D01*
X479362Y138980D01*
X354862D01*
X340150Y153692D01*
Y196486D01*
X329157Y207479D01*
Y242256D01*
X314657Y256756D01*
Y258814D01*
X299911Y273560D01*
X292342D01*
X263442Y302459D01*
Y329762D01*
X259654Y333550D01*
X232950D01*
X230000Y336500D01*
G01X715748Y29922D02*
X713253Y32417D01*
Y54569D01*
X710422Y57400D01*
X703615D01*
X678375Y32160D01*
X652304D01*
X648449Y36015D01*
X629423D01*
X586552Y78886D01*
X542285D01*
X480191Y140980D01*
X355691D01*
X342150Y154521D01*
Y197315D01*
X331157Y208308D01*
Y243085D01*
X317958Y256284D01*
Y258342D01*
X300740Y275560D01*
X293438D01*
X267500Y301498D01*
Y328719D01*
X260669Y335550D01*
X234450D01*
X233400Y336600D01*
G01X308591Y68928D02*
X352269D01*
X362333Y58864D01*
Y33730D01*
X366929Y29134D01*
G01Y34646D02*
X364334Y37241D01*
Y59692D01*
X352952Y71074D01*
X306737D01*
X304591Y68928D01*
G01X374016Y24410D02*
X369420Y29006D01*
Y57435D01*
X353781Y73074D01*
X308591D01*
G01X300311Y60800D02*
X345164D01*
X348160Y57804D01*
Y33730D01*
X352756Y29134D01*
G01X300385Y108227D02*
X311942Y96670D01*
X363425D01*
X406853Y53242D01*
Y37242D01*
X409449Y34646D01*
G01X311182Y62800D02*
X347989D01*
X350161Y60628D01*
Y37241D01*
X352756Y34646D01*
G01X272937Y90362D02*
Y89367D01*
X275402Y86902D01*
Y81757D01*
X292359Y64800D01*
X348818D01*
X355247Y58371D01*
Y29006D01*
X359843Y24410D01*
G01X266895Y100227D02*
Y99098D01*
X299193Y66800D01*
X351568D01*
X357248Y61120D01*
Y32517D01*
X359843Y29922D01*
G01X306280Y82574D02*
X357718D01*
X383594Y56698D01*
Y35691D01*
X383604Y35681D01*
Y33611D01*
X383594Y33601D01*
Y29005D01*
X388189Y24410D01*
G01Y29922D02*
X385604Y32507D01*
Y36510D01*
X385594Y36520D01*
Y57527D01*
X358547Y84574D01*
X303280D01*
X301280Y82574D01*
G01X374016Y29922D02*
Y30224D01*
X371480Y32760D01*
Y58204D01*
X354610Y75074D01*
X306591D01*
X304591Y73074D01*
G01X279385Y100227D02*
Y99993D01*
X290804Y88574D01*
X360205D01*
X392657Y56122D01*
Y37265D01*
X395276Y34646D01*
G01X292030Y90574D02*
X361034D01*
X397767Y53841D01*
Y29006D01*
X402363Y24410D01*
G01X395276Y29134D02*
X390657Y33753D01*
Y55293D01*
X359376Y86574D01*
X300280D01*
X296280Y82574D01*
G01X266406Y277835D02*
X269393Y274848D01*
X279466D01*
X290286Y264028D01*
X293402D01*
X300264Y257166D01*
Y252578D01*
X306303Y246539D01*
Y241042D01*
X307930Y239415D01*
X309974D01*
X317157Y232232D01*
Y199324D01*
X327940Y188541D01*
Y144344D01*
X350114Y122170D01*
X368909D01*
X368910Y122171D01*
X390667D01*
X456429Y56409D01*
Y33594D01*
X451969Y29134D01*
G01Y34646D02*
X454429Y37106D01*
Y55580D01*
X389839Y120170D01*
X388395D01*
X388394Y120171D01*
X369739D01*
X369738Y120170D01*
X349285D01*
X325940Y143515D01*
Y187712D01*
X315157Y198495D01*
Y228832D01*
X310239Y233750D01*
X307808D01*
X304302Y237256D01*
Y243934D01*
X298263Y249973D01*
Y256338D01*
X292573Y262028D01*
X289457D01*
X278637Y272848D01*
X267787D01*
X262800Y277835D01*
G01X306292Y252825D02*
X321157Y237960D01*
Y201898D01*
X331940Y191115D01*
Y146002D01*
X348142Y129800D01*
X476897D01*
X537811Y68886D01*
X579500D01*
X627197Y21189D01*
X636804D01*
X647216Y31601D01*
G01X302262Y262642D02*
X306020Y258884D01*
Y256246D01*
X323157Y239109D01*
Y202727D01*
X333940Y191944D01*
Y146831D01*
X348571Y132200D01*
X477326D01*
X538640Y70886D01*
X580329D01*
X628026Y23189D01*
X635432D01*
X643816Y31573D01*
G01X440945Y291339D02*
Y290845D01*
X439195Y289095D01*
Y286696D01*
X433999Y281500D01*
X432849D01*
X431015Y279666D01*
Y279216D01*
X429652Y277853D01*
X388725D01*
X385478Y281100D01*
X369621D01*
X369121Y280600D01*
Y278478D01*
X368621Y277978D01*
X367621D01*
X367121Y278478D01*
Y280600D01*
X366621Y281100D01*
X365621D01*
X365121Y280600D01*
Y278478D01*
X364621Y277978D01*
X363621D01*
X363121Y278478D01*
Y280600D01*
X362621Y281100D01*
X361621D01*
X361121Y280600D01*
Y278478D01*
X360621Y277978D01*
X359093D01*
X351809Y285262D01*
X336738D01*
X316800Y305200D01*
X308180D01*
G01X440945Y287402D02*
Y286069D01*
X435139Y280263D01*
Y279404D01*
X433529Y277794D01*
X433081D01*
X431269Y275982D01*
Y275533D01*
X429536Y273800D01*
X389000D01*
X387000Y275800D01*
X382433D01*
X381933Y276300D01*
Y278500D01*
X381433Y279000D01*
X380433D01*
X379933Y278500D01*
Y276300D01*
X379433Y275800D01*
X378433D01*
X377933Y276300D01*
Y278500D01*
X377433Y279000D01*
X376433D01*
X375933Y278500D01*
Y276300D01*
X375433Y275800D01*
X374433D01*
X373933Y276300D01*
Y278500D01*
X373433Y279000D01*
X372433D01*
X371933Y278500D01*
Y276300D01*
X371433Y275800D01*
X358400D01*
X350938Y283262D01*
X330438D01*
X324700Y289000D01*
Y292245D01*
X314045Y302900D01*
G01X750550Y135200D02*
X771150Y114600D01*
Y101921D01*
X766542Y97313D01*
X753633D01*
X751668Y95348D01*
X740483D01*
X739336Y96495D01*
X718707D01*
X712736Y90524D01*
Y86755D01*
X710270Y84289D01*
X619658D01*
X600027Y103920D01*
X552092D01*
X486513Y169499D01*
X437172D01*
X410171Y196500D01*
X394900D01*
X372810Y218590D01*
X366127D01*
X353554Y231163D01*
Y237662D01*
X338279Y252937D01*
Y257095D01*
X322994Y272380D01*
X318065D01*
X304886Y285559D01*
X304449D01*
X301358Y288650D01*
X299635D01*
G01X292225Y288267D02*
X297029D01*
X301721Y283575D01*
X304041D01*
X317236Y270380D01*
X322165D01*
X336279Y256266D01*
Y252108D01*
X351554Y236833D01*
Y230334D01*
X365298Y216590D01*
X371639D01*
X394229Y194000D01*
X407171D01*
X433672Y167499D01*
X485684D01*
X551263Y101920D01*
X599198D01*
X618829Y82289D01*
X711099D01*
X714962Y86152D01*
Y89921D01*
X719536Y94495D01*
X738507D01*
X739654Y93348D01*
X752497D01*
X754462Y95313D01*
X767533D01*
X778450Y106230D01*
Y127867D01*
X767992Y138325D01*
X759596D01*
X749971Y147950D01*
X742600D01*
X737880Y152670D01*
X729247D01*
X728271Y153646D01*
Y158979D01*
X729921Y160629D01*
G01X281150Y332000D02*
X278579Y329429D01*
Y293248D01*
X294267Y277560D01*
X301569D01*
X315180Y263949D01*
X317572D01*
X321831Y259690D01*
Y258256D01*
X322914Y257173D01*
X326298D01*
X330279Y253192D01*
Y249621D01*
X345140Y234760D01*
Y228261D01*
X350146Y223255D01*
Y219874D01*
X359430Y210590D01*
X368411D01*
X392501Y186500D01*
X404371D01*
X429372Y161499D01*
X483197D01*
X548776Y95920D01*
X596711D01*
X616342Y76289D01*
X722929D01*
X727885Y81245D01*
X746781D01*
X763560Y64466D01*
Y59820D01*
G01X452300Y337500D02*
X452550Y337750D01*
Y351733D01*
X444302Y359981D01*
X331730D01*
X327458Y355709D01*
X322109D01*
X322100Y355700D01*
X321800D01*
X318401Y352301D01*
X316501D01*
X310700Y346500D01*
X302600D01*
X300400Y344300D01*
X275700D01*
X275200Y344800D01*
Y346079D01*
X275700Y346579D01*
X297021D01*
G01X456550Y337500D02*
Y353391D01*
X445960Y363981D01*
X330072D01*
X325800Y359709D01*
X319580D01*
X317371Y357500D01*
X289800D01*
X287775Y355475D01*
X277500D01*
X277000Y354975D01*
Y353700D01*
X277500Y353200D01*
X286700D01*
X287350Y352550D01*
Y351200D01*
G01X325200Y365100D02*
X316055D01*
X315555Y364600D01*
Y362000D01*
X315055Y361500D01*
X314055D01*
X313555Y362000D01*
Y364600D01*
X313055Y365100D01*
X312055D01*
X311555Y364600D01*
Y362100D01*
X311055Y361600D01*
X310055D01*
X309555Y362100D01*
Y364600D01*
X309055Y365100D01*
X308055D01*
X307555Y364600D01*
Y362100D01*
X307055Y361600D01*
X306055D01*
X305555Y362100D01*
Y364600D01*
X305055Y365100D01*
X304055D01*
X303555Y364600D01*
Y362100D01*
X303055Y361600D01*
X302055D01*
X301555Y362100D01*
Y364600D01*
X301055Y365100D01*
X300055D01*
X299555Y364600D01*
Y362200D01*
X299055Y361700D01*
X298055D01*
X297555Y362200D01*
Y364600D01*
X297055Y365100D01*
X294700D01*
X294200Y365600D01*
Y366824D01*
X294700Y367324D01*
X325124D01*
X329250Y371450D01*
X330406D01*
X330906Y370950D01*
Y368500D01*
X331406Y368000D01*
X332506D01*
X333006Y368500D01*
Y370800D01*
X333506Y371300D01*
X334506D01*
X335006Y370800D01*
Y368500D01*
X335506Y368000D01*
X336506D01*
X337006Y368500D01*
Y370600D01*
X337956Y371550D01*
X345819D01*
X347388Y369981D01*
X448725D01*
X462550Y356156D01*
Y339893D01*
X464300Y338143D01*
Y337500D01*
G01X448300D02*
Y346246D01*
X444496Y350050D01*
X444233D01*
X442355Y351928D01*
Y352634D01*
X443706Y353986D01*
Y354692D01*
X442997Y355401D01*
X442291D01*
X440940Y354049D01*
X440234D01*
X438510Y355773D01*
X334073D01*
X326300Y348000D01*
X324600D01*
X324100Y347500D01*
Y345800D01*
X323619Y345319D01*
X322300D01*
X321800Y345819D01*
Y348371D01*
X319871Y350300D01*
X317329D01*
X311529Y344500D01*
X303429D01*
X301229Y342300D01*
X294400D01*
X293900Y341800D01*
Y340213D01*
X294400Y339713D01*
X302686D01*
X305300Y342327D01*
X312427D01*
X317269Y347169D01*
X319550D01*
G01X452755Y303150D02*
X454618Y305013D01*
Y309021D01*
X453800Y309839D01*
Y316026D01*
X454400Y316626D01*
Y319100D01*
X455450Y320150D01*
Y335771D01*
X454550Y336671D01*
Y352562D01*
X445131Y361981D01*
X330901D01*
X326629Y357709D01*
X321280D01*
X321271Y357700D01*
X320971D01*
X317572Y354301D01*
X314874D01*
X314408Y354767D01*
X313891Y355283D01*
X313185D01*
X312476Y354574D01*
Y353868D01*
X313505Y352840D01*
Y352134D01*
X310285Y348914D01*
X290786D01*
X289900Y349800D01*
Y354771D01*
X290629Y355500D01*
X302100D01*
X302600Y355000D01*
Y353900D01*
X302100Y353400D01*
X293500D01*
X293000Y352900D01*
Y351600D01*
X293500Y351100D01*
X309400D01*
X309900Y351600D01*
Y354206D01*
X309400Y354706D01*
X305147D01*
G01X448819Y307088D02*
Y308513D01*
X451500Y311194D01*
Y316556D01*
X452400Y317456D01*
Y320199D01*
X452950Y320749D01*
Y329923D01*
X446101Y336772D01*
Y345616D01*
X443667Y348050D01*
X443404D01*
X440737Y350717D01*
X440029D01*
X439210Y349898D01*
X438502D01*
X437795Y350605D01*
Y351313D01*
X438614Y352132D01*
Y352840D01*
X437681Y353773D01*
X335435D01*
X335381Y353719D01*
X334881D01*
X323489Y342327D01*
X321024D01*
X320524Y342827D01*
Y344100D01*
X320024Y344600D01*
X319024D01*
X318524Y344100D01*
Y343100D01*
X318024Y342600D01*
X316450D01*
X316050Y342200D01*
G01X460800Y337562D02*
X460550Y337812D01*
Y355327D01*
X447896Y367981D01*
X339481D01*
X337481Y365981D01*
X329243D01*
X324971Y361709D01*
X318593D01*
X316384Y359500D01*
X294259D01*
X289600Y364159D01*
X274200D01*
X273700Y363659D01*
Y362500D01*
X274200Y362000D01*
X287900D01*
X288400Y361500D01*
Y360500D01*
X287900Y360000D01*
X271300D01*
X270800Y359500D01*
Y358200D01*
X271300Y357700D01*
X287350D01*
G01X448818Y303151D02*
X451027Y305360D01*
Y307903D01*
X452800Y309676D01*
Y316441D01*
X453400Y317041D01*
Y319600D01*
X454450Y320650D01*
Y333450D01*
X452401Y335499D01*
X451472D01*
X450300Y336671D01*
Y351154D01*
X443473Y357981D01*
X333452D01*
X329171Y353700D01*
X325644D01*
X325144Y353200D01*
Y350500D01*
X324644Y350000D01*
X323000D01*
X322500Y350500D01*
Y353700D01*
G01X301500Y337500D02*
X298000D01*
X297500Y337000D01*
Y327200D01*
X298000Y326700D01*
X299300D01*
X299800Y327200D01*
Y334200D01*
X300300Y334700D01*
X301300D01*
X301800Y334200D01*
Y327100D01*
X302300Y326600D01*
X303651D01*
X304151Y327100D01*
Y338349D01*
X306129Y340327D01*
X310302D01*
X312765Y337864D01*
X316535D01*
X318998Y340327D01*
X327973D01*
X329419Y341773D01*
X333624D01*
X334124Y342273D01*
Y343800D01*
X334624Y344300D01*
X335624D01*
X336124Y343800D01*
Y342273D01*
X336624Y341773D01*
X344224D01*
X346797Y339200D01*
X403000D01*
X404926Y337274D01*
X416912D01*
X419336Y334850D01*
X445188D01*
X450950Y329088D01*
Y321851D01*
X450400Y321301D01*
Y318286D01*
X449462Y317348D01*
X447269D01*
X444882Y314961D01*
G01Y318898D02*
X445098D01*
X448950Y322750D01*
Y328258D01*
X444358Y332850D01*
X437682D01*
X433345Y328513D01*
X428646D01*
X425581Y331578D01*
X386382D01*
X385282Y330478D01*
X347032D01*
X342028Y335482D01*
X321624D01*
X320650Y336456D01*
G01X433071Y314961D02*
X434561D01*
X436400Y316800D01*
X441040D01*
X443200Y318960D01*
Y319701D01*
X444599Y321100D01*
X445799D01*
X447950Y323251D01*
Y327843D01*
X443943Y331850D01*
X438109D01*
X433772Y327513D01*
X428231D01*
X425166Y330578D01*
X386797D01*
X384425Y328206D01*
X346475D01*
X341199Y333482D01*
X310218D01*
X306060Y337640D01*
G01X310200Y337600D02*
X312100Y335700D01*
X317200D01*
X319827Y338327D01*
X328802D01*
X330248Y339773D01*
X343395D01*
X347834Y335334D01*
X384413D01*
X386159Y337080D01*
G01X440945Y299213D02*
Y298982D01*
X442700Y297227D01*
Y294300D01*
X441499Y293099D01*
X440100D01*
X438758Y291757D01*
Y290658D01*
X437503Y289403D01*
X436432D01*
X434998Y287969D01*
Y286698D01*
X433468Y285168D01*
X431969D01*
X428501Y281700D01*
X388500D01*
X386922Y283278D01*
X356622D01*
X352638Y287262D01*
X337838D01*
X331336Y293764D01*
Y294472D01*
X332228Y295364D01*
Y296072D01*
X331521Y296779D01*
X330813D01*
X329921Y295887D01*
X329213D01*
X328506Y296594D01*
Y297302D01*
X329398Y298194D01*
Y298902D01*
X328691Y299609D01*
X327983D01*
X327091Y298717D01*
X326383D01*
X325676Y299424D01*
Y300132D01*
X326568Y301024D01*
Y301732D01*
X325861Y302439D01*
X325153D01*
X324261Y301547D01*
X323553D01*
X322846Y302254D01*
Y302962D01*
X323738Y303854D01*
Y304562D01*
X323031Y305269D01*
X322323D01*
X321431Y304377D01*
X320723D01*
X316641Y308459D01*
X314241D01*
G01X440945Y303150D02*
X438995Y301200D01*
X436400D01*
X435048Y299848D01*
Y298549D01*
X433846Y297347D01*
X432547D01*
X431302Y296102D01*
Y294903D01*
X429899Y293500D01*
X387607D01*
X382524Y298583D01*
X372279D01*
X371779Y298083D01*
Y296700D01*
X371279Y296200D01*
X370279D01*
X369779Y296700D01*
Y298083D01*
X369279Y298583D01*
X368279D01*
X367779Y298083D01*
Y296700D01*
X367279Y296200D01*
X366279D01*
X365779Y296700D01*
Y298083D01*
X365279Y298583D01*
X364279D01*
X363779Y298083D01*
Y296700D01*
X363279Y296200D01*
X362279D01*
X361779Y296700D01*
Y298083D01*
X361279Y298583D01*
X360279D01*
X359779Y298083D01*
Y296700D01*
X359279Y296200D01*
X358279D01*
X357779Y296700D01*
Y298083D01*
X357279Y298583D01*
X356279D01*
X355779Y298083D01*
Y296700D01*
X355279Y296200D01*
X354279D01*
X353779Y296700D01*
Y298083D01*
X353279Y298583D01*
X352279D01*
X351779Y298083D01*
Y296700D01*
X351279Y296200D01*
X350279D01*
X349779Y296700D01*
Y298083D01*
X349279Y298583D01*
X338610D01*
X325893Y311300D01*
X314900D01*
X314300Y311900D01*
G01X440945Y311024D02*
X438921Y309000D01*
X436200D01*
X434971Y307771D01*
Y306370D01*
X433601Y305000D01*
X432400D01*
X431341Y303941D01*
Y302840D01*
X429495Y300994D01*
X386908D01*
X382428Y305474D01*
X377274D01*
X374383Y302583D01*
X350091D01*
X347874Y304800D01*
X345000D01*
X342900Y302700D01*
X340151D01*
X326906Y315945D01*
X310194D01*
X305628Y320511D01*
G01X301628D02*
X308194Y313945D01*
X326077D01*
X339439Y300583D01*
X384052D01*
X387235Y297400D01*
X429900D01*
X431200Y298700D01*
Y299899D01*
X432626Y301325D01*
X433825D01*
X434932Y302432D01*
Y303578D01*
X436657Y305303D01*
X439161D01*
X440945Y307087D01*
G01X314400Y327851D02*
X315149Y328600D01*
X317046D01*
X317546Y328100D01*
Y325900D01*
X318046Y325400D01*
X319046D01*
X319546Y325900D01*
Y327900D01*
X320046Y328400D01*
X321046D01*
X321546Y327900D01*
Y325900D01*
X322046Y325400D01*
X323046D01*
X323546Y325900D01*
Y326900D01*
X324046Y327400D01*
X338000D01*
X345428Y319972D01*
X370401D01*
X372529Y322100D01*
X385389D01*
X388059Y324770D01*
X426729D01*
X427899Y323600D01*
X437800D01*
X441404Y327204D01*
X442913D01*
G01X440944Y322835D02*
X439709Y321600D01*
X429099D01*
X427000Y319501D01*
Y318200D01*
X425600Y316800D01*
X388900D01*
X385827Y313727D01*
X383200D01*
X380927Y316000D01*
X377900D01*
X375627Y313727D01*
X373400D01*
X371155Y315972D01*
X366472D01*
X364227Y313727D01*
X352675D01*
X352175Y314227D01*
Y315000D01*
X351675Y315500D01*
X350675D01*
X350175Y315000D01*
Y314227D01*
X349675Y313727D01*
X343256D01*
X341791Y315192D01*
Y317808D01*
X336199Y323400D01*
X316600D01*
X315749Y324251D01*
X314500D01*
G01X438976Y327204D02*
X437864D01*
X435260Y324600D01*
X428314D01*
X424336Y328578D01*
X389128D01*
X384650Y324100D01*
X371700D01*
X369572Y321972D01*
X358300D01*
X357800Y322472D01*
Y323600D01*
X357300Y324100D01*
X356300D01*
X355800Y323600D01*
Y322472D01*
X355300Y321972D01*
X354300D01*
X353800Y322472D01*
Y323600D01*
X353300Y324100D01*
X352300D01*
X351800Y323600D01*
Y322472D01*
X351300Y321972D01*
X346328D01*
X338900Y329400D01*
X326500D01*
X325300Y330600D01*
X319100D01*
G01X437008Y318898D02*
X434910Y316800D01*
X432201D01*
X430992Y315591D01*
Y310293D01*
X429999Y309300D01*
X381003D01*
X380829Y309474D01*
X341726D01*
X337527Y313673D01*
X335471D01*
X329785Y319359D01*
X310780D01*
X305628Y324511D01*
G01X324100Y307814D02*
X327656Y304258D01*
Y303879D01*
X342273Y289262D01*
X354356D01*
X357918Y285700D01*
X358918D01*
X359418Y286200D01*
Y288900D01*
X359918Y289400D01*
X360918D01*
X361418Y288900D01*
Y286200D01*
X361918Y285700D01*
X362918D01*
X363418Y286200D01*
Y288900D01*
X363918Y289400D01*
X368007D01*
X368507Y288900D01*
Y286000D01*
X369007Y285500D01*
X370007D01*
X370507Y286000D01*
Y288900D01*
X371007Y289400D01*
X372007D01*
X372507Y288900D01*
Y286000D01*
X373007Y285500D01*
X374007D01*
X374507Y286000D01*
Y288900D01*
X375007Y289400D01*
X376007D01*
X376507Y288900D01*
Y286000D01*
X377007Y285500D01*
X378007D01*
X378507Y286000D01*
Y288900D01*
X379007Y289400D01*
X383630D01*
X387530Y285500D01*
X429700D01*
X431031Y286831D01*
Y287792D01*
X432630Y289391D01*
X433500D01*
X435164Y291055D01*
Y291979D01*
X437008Y293823D01*
Y295276D01*
G01X308398Y386479D02*
X312419Y390500D01*
X353000D01*
X355519Y387981D01*
X475336D01*
X487400Y375917D01*
Y363665D01*
X489350Y361715D01*
Y355349D01*
X493877Y350822D01*
Y337371D01*
X483900Y327394D01*
Y321300D01*
X482400Y319800D01*
Y314301D01*
X476347Y308248D01*
Y305800D01*
X474799Y304252D01*
Y302699D01*
X473300Y301200D01*
X471200D01*
X470300Y300300D01*
Y298300D01*
X465389Y293389D01*
X459700D01*
X458800Y292489D01*
Y290200D01*
X457682Y289082D01*
X454435D01*
X452755Y287402D01*
G01X304205Y382450D02*
Y378543D01*
X304705Y378043D01*
X307749D01*
X308249Y378543D01*
Y381056D01*
X308749Y381556D01*
X309749D01*
X310249Y381056D01*
Y378543D01*
X310749Y378043D01*
X311749D01*
X312249Y378543D01*
Y381056D01*
X312749Y381556D01*
X313749D01*
X314249Y381056D01*
Y378500D01*
X314749Y378000D01*
X315749D01*
X316249Y378500D01*
Y381056D01*
X316749Y381556D01*
X317749D01*
X318249Y381056D01*
Y378326D01*
X318749Y377826D01*
X319749D01*
X320249Y378326D01*
Y381056D01*
X320749Y381556D01*
X321749D01*
X322249Y381056D01*
Y378239D01*
X322749Y377739D01*
X323749D01*
X324249Y378239D01*
Y381056D01*
X324749Y381556D01*
X325749D01*
X326249Y381056D01*
Y380050D01*
X326749Y379550D01*
X349135D01*
X350704Y377981D01*
X457960D01*
X459205Y376736D01*
X459739D01*
X460943Y377940D01*
X461651D01*
X462358Y377233D01*
Y376525D01*
X461154Y375321D01*
Y374787D01*
X462035Y373906D01*
X462569D01*
X463773Y375110D01*
X464481D01*
X465188Y374403D01*
Y373695D01*
X463984Y372491D01*
Y371957D01*
X464865Y371076D01*
X465399D01*
X466603Y372280D01*
X467311D01*
X468018Y371573D01*
Y370865D01*
X466814Y369661D01*
Y369127D01*
X473212Y362729D01*
Y357186D01*
X474350Y356047D01*
Y343091D01*
X473308Y342049D01*
Y336735D01*
X469405Y332832D01*
Y331771D01*
X470542Y330634D01*
Y329926D01*
X469835Y329219D01*
X469127D01*
X467488Y330858D01*
X466780D01*
X466073Y330151D01*
Y329443D01*
X467712Y327804D01*
Y327420D01*
X464184Y323892D01*
X460162D01*
X459662Y323392D01*
Y321442D01*
X460162Y320942D01*
X462300D01*
X463017Y320225D01*
Y317983D01*
X462158Y317124D01*
X460600D01*
X458800Y315324D01*
Y309194D01*
X456693Y307087D01*
G01X304398Y386479D02*
X307244Y383633D01*
X327608D01*
X329691Y381550D01*
X349964D01*
X351533Y379981D01*
X462940D01*
X470050Y372871D01*
Y368821D01*
X475212Y363659D01*
Y358039D01*
X476350Y356899D01*
X476556Y356693D01*
Y354222D01*
X477056Y353722D01*
X478802D01*
X479302Y353222D01*
Y352222D01*
X478802Y351722D01*
X476861D01*
X476361Y351222D01*
Y350222D01*
X476861Y349722D01*
X478954D01*
X479454Y349222D01*
Y346119D01*
X478954Y345619D01*
X476903D01*
X476403Y345119D01*
Y344119D01*
X476903Y343619D01*
X480567D01*
X481067Y343119D01*
Y342119D01*
X480567Y341619D01*
X475918D01*
X475418Y341119D01*
Y340119D01*
X475918Y339619D01*
X479504D01*
X480004Y339119D01*
Y338119D01*
X479504Y337619D01*
X476419D01*
X474196Y335396D01*
Y334093D01*
X473696Y333593D01*
X471938D01*
X471438Y333093D01*
Y332093D01*
X471938Y331593D01*
X473696D01*
X474196Y331093D01*
Y325935D01*
X473096Y324835D01*
X467100D01*
X466600Y324335D01*
Y323335D01*
X467100Y322835D01*
X470005D01*
X470505Y322335D01*
Y321335D01*
X470005Y320835D01*
X467100D01*
X466600Y320335D01*
Y317881D01*
X460630Y311911D01*
Y311024D01*
G01X292800Y363800D02*
X290441Y366159D01*
X274100D01*
X273600Y366659D01*
Y368824D01*
X274100Y369324D01*
X277389D01*
X277889Y369824D01*
Y373400D01*
X278389Y373900D01*
X279389D01*
X279889Y373400D01*
Y369824D01*
X280389Y369324D01*
X281389D01*
X281889Y369824D01*
Y375800D01*
X282389Y376300D01*
X283389D01*
X283889Y375800D01*
Y369824D01*
X284389Y369324D01*
X285389D01*
X285889Y369824D01*
Y375700D01*
X286389Y376200D01*
X287389D01*
X287889Y375700D01*
Y369824D01*
X288389Y369324D01*
X323895D01*
X328121Y373550D01*
X346648D01*
X348217Y371981D01*
X449554D01*
X460340Y361195D01*
X462832D01*
X464576Y359451D01*
Y349951D01*
X466350Y348177D01*
Y346576D01*
X464550Y344776D01*
Y340722D01*
X466350Y338922D01*
Y334872D01*
X465687Y334209D01*
X464979D01*
X462987Y336201D01*
X462279D01*
X461572Y335494D01*
Y334786D01*
X463564Y332794D01*
Y332086D01*
X462599Y331121D01*
Y327204D01*
G01X456693Y311024D02*
X454900Y312817D01*
Y315617D01*
X456054Y316771D01*
X458056D01*
X458556Y317271D01*
Y325000D01*
X459056Y325500D01*
X463300D01*
X464433Y326633D01*
Y330804D01*
X471308Y337679D01*
Y342878D01*
X472350Y343920D01*
Y354144D01*
X471134Y355364D01*
Y361978D01*
X468293Y364819D01*
X467671D01*
X466892Y364040D01*
X466184D01*
X465477Y364747D01*
Y365455D01*
X466256Y366234D01*
Y366856D01*
X465463Y367649D01*
X464841D01*
X462668Y365476D01*
X461960D01*
X461253Y366183D01*
Y366891D01*
X463426Y369064D01*
Y369686D01*
X462633Y370479D01*
X462011D01*
X459896Y368364D01*
X459190D01*
X458482Y369074D01*
Y369780D01*
X460596Y371894D01*
Y372516D01*
X459803Y373309D01*
X459181D01*
X457154Y371282D01*
X456446D01*
X455739Y371989D01*
Y372958D01*
X457419Y374638D01*
Y375260D01*
X456698Y375981D01*
X349875D01*
X348306Y377550D01*
X326463D01*
X322237Y373324D01*
X320890D01*
X320346Y373868D01*
Y375333D01*
X319853Y375826D01*
X318839D01*
X318346Y375333D01*
Y373868D01*
X317846Y373368D01*
X316846D01*
X316346Y373868D01*
Y375333D01*
X315846Y375833D01*
X314846D01*
X314346Y375333D01*
Y373868D01*
X313846Y373368D01*
X312846D01*
X312346Y373868D01*
Y375333D01*
X311846Y375833D01*
X310846D01*
X310346Y375333D01*
Y373868D01*
X309846Y373368D01*
X308846D01*
X308346Y373868D01*
Y375333D01*
X307846Y375833D01*
X306846D01*
X306346Y375333D01*
Y373868D01*
X305846Y373368D01*
X304846D01*
X304346Y373868D01*
Y375722D01*
X303846Y376222D01*
X302846D01*
X302346Y375722D01*
Y373868D01*
X301846Y373368D01*
X295800D01*
X295300Y373868D01*
Y375865D01*
X295800Y376365D01*
X299519D01*
X300019Y376865D01*
Y379524D01*
G01X468300Y337500D02*
X469085Y338285D01*
Y340658D01*
X468585Y341158D01*
X467123D01*
X466623Y341658D01*
Y343884D01*
X467123Y344384D01*
X469420D01*
X470350Y345314D01*
Y348809D01*
X469612Y349547D01*
X467969D01*
X467469Y350047D01*
Y351047D01*
X467969Y351547D01*
X469572D01*
X470072Y352047D01*
Y353047D01*
X469572Y353547D01*
X467427D01*
X466927Y354047D01*
Y355047D01*
X467427Y355547D01*
X468412D01*
X469053Y356188D01*
Y358164D01*
X464022Y363195D01*
X461169D01*
X453129Y371235D01*
Y371943D01*
X453735Y372549D01*
Y373257D01*
X453028Y373964D01*
X452320D01*
X451714Y373358D01*
X451006D01*
X450383Y373981D01*
X349046D01*
X347477Y375550D01*
X327292D01*
X323066Y371324D01*
X290438D01*
X289938Y371824D01*
Y373163D01*
X290438Y373663D01*
X292495D01*
X292995Y374163D01*
Y375163D01*
X292495Y375663D01*
X290438D01*
X289938Y376163D01*
Y377163D01*
X290438Y377663D01*
X292459D01*
X292959Y378163D01*
Y382529D01*
X301732Y391302D01*
X307422D01*
X307922Y390802D01*
Y388979D01*
X307422Y388479D01*
X302954D01*
X296079Y381604D01*
Y379524D01*
G01X312398Y386479D02*
X314558D01*
X315058Y386979D01*
Y387930D01*
X315558Y388430D01*
X316558D01*
X317058Y387930D01*
Y386329D01*
X317558Y385829D01*
X318558D01*
X319058Y386329D01*
Y387930D01*
X319558Y388430D01*
X320558D01*
X321058Y387930D01*
Y386243D01*
X321558Y385743D01*
X322558D01*
X323058Y386243D01*
Y387930D01*
X323558Y388430D01*
X324558D01*
X325058Y387930D01*
Y386133D01*
X325558Y385633D01*
X326558D01*
X327058Y386133D01*
Y387930D01*
X327558Y388430D01*
X328558D01*
X329058Y387930D01*
Y385012D01*
X330520Y383550D01*
X350793D01*
X352362Y381981D01*
X463769D01*
X472050Y373700D01*
Y371033D01*
X473233Y369850D01*
X475831D01*
X479212Y366469D01*
Y359697D01*
X483350Y355559D01*
Y352862D01*
X487877Y348335D01*
Y347039D01*
X487377Y346539D01*
X486120D01*
X485620Y346039D01*
Y345039D01*
X486120Y344539D01*
X487377D01*
X487877Y344039D01*
Y340160D01*
X476925Y329208D01*
Y324067D01*
X474200Y321342D01*
Y317749D01*
X473200Y316749D01*
X471649D01*
X470600Y315700D01*
Y313437D01*
X469891Y312728D01*
X467425D01*
X466425Y311728D01*
Y306425D01*
X465128Y305128D01*
X459600D01*
X458600Y304128D01*
Y301974D01*
X457600Y300974D01*
X456063D01*
X454707Y299618D01*
Y298799D01*
X452755Y296847D01*
Y295277D01*
G01X335722Y94574D02*
X362692D01*
X404853Y52413D01*
Y33730D01*
X409449Y29134D01*
G01X329722Y94574D02*
X331722Y92574D01*
X361863D01*
X399768Y54669D01*
Y53013D01*
X399767Y53012D01*
Y32518D01*
X402363Y29922D01*
G01X750773Y74636D02*
X731984D01*
X726243Y68895D01*
X699395D01*
X674519Y44019D01*
X660639D01*
X657058Y47600D01*
X648871D01*
X639971Y56500D01*
X616415D01*
X588995Y83920D01*
X543802D01*
X481871Y145851D01*
X427378D01*
X400658Y172571D01*
X374809D01*
X374616Y172378D01*
G01X747919Y76667D02*
X731114D01*
X725342Y70895D01*
X696395D01*
X671519Y46019D01*
X661468D01*
X657887Y49600D01*
X649700D01*
X640800Y58500D01*
X618091D01*
X590671Y85920D01*
X544631D01*
X481531Y149020D01*
X427562D01*
X402011Y174571D01*
X372199D01*
X370061Y172433D01*
G01X744094Y29922D02*
X741552Y32464D01*
Y54616D01*
X732339Y63829D01*
X701283D01*
X675614Y38160D01*
X663008D01*
X655668Y45500D01*
X623613D01*
X588227Y80886D01*
X543114D01*
X481000Y143000D01*
X357000D01*
X355500Y144500D01*
G01X349911Y136954D02*
X349937Y136980D01*
X478533D01*
X540627Y74886D01*
X583127D01*
X626786Y31227D01*
G01X376306Y182715D02*
X405327D01*
X428543Y159499D01*
X482368D01*
X547947Y93920D01*
X595882D01*
X618302Y71500D01*
X638312D01*
X641003Y68809D01*
G01X627500Y64500D02*
X619644D01*
X594224Y89920D01*
X546289D01*
X481866Y154343D01*
X427897D01*
X403634Y178606D01*
X371278D01*
X371124Y178760D01*
G01X664301Y49998D02*
X659149Y55150D01*
X647850D01*
X633500Y69500D01*
X617473D01*
X595053Y91920D01*
X547118D01*
X481780Y157258D01*
X427811D01*
X404463Y180606D01*
X375586D01*
X373830Y182362D01*
X372517D01*
G01D02*
Y202550D01*
X367872Y207195D01*
X359218D01*
X348000Y218413D01*
Y222572D01*
X343140Y227432D01*
Y233931D01*
X328134Y248937D01*
Y252720D01*
G01X374915Y176442D02*
X375079Y176606D01*
X402805D01*
X427856Y151555D01*
X481825D01*
X545460Y87920D01*
X592220D01*
X618640Y61500D01*
X629500D01*
G01X331026Y303354D02*
Y303338D01*
X340314Y294050D01*
X341366D01*
X341866Y294550D01*
Y296000D01*
X342366Y296500D01*
X343366D01*
X343866Y296000D01*
Y294550D01*
X344366Y294050D01*
X350786D01*
X351286Y293550D01*
Y291900D01*
X351786Y291400D01*
X352786D01*
X353286Y291900D01*
Y293550D01*
X353786Y294050D01*
X354786D01*
X355286Y293550D01*
Y291900D01*
X355786Y291400D01*
X356786D01*
X357286Y291900D01*
Y293550D01*
X357786Y294050D01*
X358786D01*
X359286Y293550D01*
Y291900D01*
X359786Y291400D01*
X360786D01*
X361286Y291900D01*
Y293550D01*
X361786Y294050D01*
X362786D01*
X363286Y293550D01*
Y291900D01*
X363786Y291400D01*
X364786D01*
X365286Y291900D01*
Y293550D01*
X365786Y294050D01*
X366786D01*
X367286Y293550D01*
Y291900D01*
X367786Y291400D01*
X368786D01*
X369286Y291900D01*
Y293550D01*
X369786Y294050D01*
X370786D01*
X371286Y293550D01*
Y291900D01*
X371786Y291400D01*
X372786D01*
X373286Y291900D01*
Y295200D01*
X373786Y295700D01*
X374786D01*
X375286Y295200D01*
Y291900D01*
X375786Y291400D01*
X376786D01*
X377286Y291900D01*
Y295200D01*
X377786Y295700D01*
X378786D01*
X379286Y295200D01*
Y291900D01*
X379786Y291400D01*
X380786D01*
X381286Y291900D01*
Y293550D01*
X381786Y294050D01*
X383901D01*
X388351Y289600D01*
X429900D01*
X431108Y290808D01*
Y291909D01*
X432299Y293100D01*
X433300D01*
X434900Y294700D01*
Y295801D01*
X436099Y297000D01*
X439221D01*
X440945Y295276D01*
G01X332000Y266336D02*
X334686Y263650D01*
X339467D01*
X360917Y242200D01*
X392706D01*
X396306Y238600D01*
X397452D01*
X399829Y236223D01*
Y234030D01*
X401575Y232284D01*
G01X421259Y240158D02*
X419259Y242158D01*
X416684D01*
X415351Y243491D01*
Y244323D01*
X414029Y245645D01*
X413580D01*
X410999Y248226D01*
Y248675D01*
X405474Y254200D01*
X383976D01*
X376633Y261543D01*
G01X340280Y253765D02*
X355845Y238200D01*
X389329D01*
X396795Y230734D01*
X398066D01*
X400159Y228641D01*
X401727D01*
G01X337500Y266050D02*
X339896D01*
X361746Y244200D01*
X395340D01*
X396995Y242545D01*
X401381D01*
X403700Y240226D01*
Y234096D01*
X405512Y232284D01*
G01X358096Y262268D02*
X373882Y246482D01*
X401381D01*
X403962Y243901D01*
Y243452D01*
X404869Y242545D01*
X405318D01*
X407500Y240363D01*
Y235977D01*
X409569Y233908D01*
X411762D01*
X413386Y232284D01*
G01X405512Y228347D02*
X403668Y230191D01*
X401475D01*
X399500Y232166D01*
Y232615D01*
X397715Y234400D01*
X396384D01*
X390584Y240200D01*
X358498D01*
X341998Y256700D01*
G01X368610Y257299D02*
X381011Y269700D01*
X413596D01*
X415773Y267523D01*
Y247389D01*
X417191Y245971D01*
X419384D01*
X421260Y244095D01*
G01X376633Y256851D02*
X383684Y249800D01*
X405937D01*
X407899Y247838D01*
Y247389D01*
X408806Y246482D01*
X409255D01*
X411736Y244001D01*
Y239616D01*
X412852Y238500D01*
X415666D01*
X417323Y240157D01*
G01X460630Y307087D02*
X459447D01*
X457443Y305083D01*
X456346D01*
X454949Y303686D01*
Y302719D01*
X453630Y301400D01*
X444439D01*
X443100Y302739D01*
Y315600D01*
X444400Y316900D01*
X445301D01*
X447200Y318799D01*
Y319516D01*
X449950Y322266D01*
Y328673D01*
X444773Y333850D01*
X436364D01*
X432027Y329513D01*
X429061D01*
X425996Y332578D01*
X347761D01*
X342566Y337773D01*
X335773D01*
X335400Y337400D01*
G01X345700Y349773D02*
X349659D01*
X350159Y349273D01*
Y347700D01*
X350659Y347200D01*
X351659D01*
X352159Y347700D01*
Y349273D01*
X352659Y349773D01*
X353659D01*
X354159Y349273D01*
Y347700D01*
X354659Y347200D01*
X355659D01*
X356159Y347700D01*
Y349273D01*
X356659Y349773D01*
X360838D01*
X361338Y349273D01*
Y347700D01*
X361838Y347200D01*
X362838D01*
X363338Y347700D01*
Y349273D01*
X363838Y349773D01*
X364838D01*
X365338Y349273D01*
Y347700D01*
X365838Y347200D01*
X366838D01*
X367338Y347700D01*
Y349273D01*
X367838Y349773D01*
X376747D01*
X377247Y349273D01*
Y347800D01*
X377747Y347300D01*
X378747D01*
X379247Y347800D01*
Y349273D01*
X379747Y349773D01*
X384505D01*
X385005Y349273D01*
Y347700D01*
X385505Y347200D01*
X386505D01*
X387005Y347700D01*
Y349273D01*
X387505Y349773D01*
X388505D01*
X389005Y349273D01*
Y347700D01*
X389505Y347200D01*
X390505D01*
X391005Y347700D01*
Y349273D01*
X391505Y349773D01*
X392505D01*
X393005Y349273D01*
Y347700D01*
X393505Y347200D01*
X394505D01*
X395005Y347700D01*
Y349273D01*
X395505Y349773D01*
X396505D01*
X397005Y349273D01*
Y347700D01*
X397505Y347200D01*
X398505D01*
X399005Y347700D01*
Y349273D01*
X399505Y349773D01*
X400505D01*
X401005Y349273D01*
Y347700D01*
X401505Y347200D01*
X402505D01*
X403005Y347700D01*
Y349273D01*
X403505Y349773D01*
X407613D01*
X408113Y349273D01*
Y347800D01*
X408613Y347300D01*
X409613D01*
X410113Y347800D01*
Y349273D01*
X410613Y349773D01*
X418083D01*
X418583Y349273D01*
Y347700D01*
X419083Y347200D01*
X420083D01*
X420583Y347700D01*
Y349273D01*
X421083Y349773D01*
X422083D01*
X422583Y349273D01*
Y347700D01*
X423083Y347200D01*
X424083D01*
X424583Y347700D01*
Y349273D01*
X425083Y349773D01*
X430994D01*
X432850Y347917D01*
Y347333D01*
X437183Y343000D01*
X442100D01*
X444100Y341000D01*
G01X337600Y349600D02*
X340800D01*
X342627Y347773D01*
X346896D01*
X349469Y345200D01*
X431700D01*
X435900Y341000D01*
X440800D01*
X444200Y337600D01*
G01X448818Y311024D02*
X450500Y312706D01*
Y316971D01*
X451400Y317871D01*
Y320800D01*
X451950Y321350D01*
Y329503D01*
X445603Y335850D01*
X432320D01*
X428270Y339900D01*
Y340700D01*
X427770Y341200D01*
X426770D01*
X426270Y340700D01*
Y339200D01*
X425770Y338700D01*
X424770D01*
X424270Y339200D01*
Y340700D01*
X423770Y341200D01*
X422770D01*
X422270Y340700D01*
Y339900D01*
X421770Y339400D01*
X420770D01*
X420270Y339900D01*
Y340700D01*
X419770Y341200D01*
X418770D01*
X418270Y340700D01*
Y339900D01*
X417770Y339400D01*
X416770D01*
X416270Y339900D01*
Y340700D01*
X415770Y341200D01*
X414770D01*
X414270Y340700D01*
Y339900D01*
X413770Y339400D01*
X412770D01*
X412270Y339900D01*
Y340700D01*
X411770Y341200D01*
X410770D01*
X410270Y340700D01*
Y339900D01*
X409770Y339400D01*
X408770D01*
X408270Y339900D01*
Y340700D01*
X407770Y341200D01*
X347626D01*
X345053Y343773D01*
X339927D01*
X339000Y344700D01*
G01X330000Y345800D02*
X335973Y351773D01*
X433644D01*
X440417Y345000D01*
X444100D01*
G01X327400Y342600D02*
X327417D01*
X328590Y343773D01*
X331108D01*
X334095Y346760D01*
X340440D01*
X341427Y345773D01*
X345882D01*
X348455Y343200D01*
X430731D01*
X436431Y337500D01*
X440300D01*
G01X386159Y337080D02*
X388705Y334534D01*
X416912D01*
X417868Y333578D01*
X426971D01*
X429286Y331263D01*
X431102D01*
G01X328100Y331300D02*
X328282Y331482D01*
X339811D01*
X345087Y326206D01*
X362511D01*
X363011Y325706D01*
Y324500D01*
X363511Y324000D01*
X364511D01*
X365011Y324500D01*
Y325706D01*
X365511Y326206D01*
X366511D01*
X367011Y325706D01*
Y324500D01*
X367511Y324000D01*
X368511D01*
X369011Y324500D01*
Y325706D01*
X369511Y326206D01*
X384546D01*
X387918Y329578D01*
X424751D01*
X427816Y326513D01*
X434962D01*
X438749Y330300D01*
X442800D01*
G01X325500Y325400D02*
X337100D01*
X344528Y317972D01*
X372522D01*
X373022Y318472D01*
Y319600D01*
X373522Y320100D01*
X374522D01*
X375022Y319600D01*
Y318600D01*
X375522Y318100D01*
X376522D01*
X377022Y318600D01*
Y319600D01*
X377522Y320100D01*
X378522D01*
X379022Y319600D01*
Y318600D01*
X379522Y318100D01*
X380522D01*
X381022Y318600D01*
Y319600D01*
X381522Y320100D01*
X382522D01*
X383022Y319600D01*
Y318600D01*
X383522Y318100D01*
X384522D01*
X385022Y318600D01*
Y319600D01*
X386561Y321139D01*
X427053D01*
X428514Y322600D01*
X438316D01*
X440316Y324600D01*
X444283D01*
X446200Y326517D01*
Y327400D01*
G01X325500Y321400D02*
X330964D01*
X332164Y320200D01*
X333434D01*
X334613Y321379D01*
X335321D01*
X336028Y320672D01*
Y319964D01*
X334436Y318372D01*
Y317664D01*
X335143Y316957D01*
X335851D01*
X337443Y318549D01*
X338151D01*
X338858Y317842D01*
Y317134D01*
X338343Y316619D01*
Y315811D01*
X342427Y311727D01*
X367016D01*
X367516Y312227D01*
Y313400D01*
X368016Y313900D01*
X369016D01*
X369516Y313400D01*
Y312227D01*
X370016Y311727D01*
X378099D01*
X378699Y312327D01*
Y313500D01*
X379199Y314000D01*
X380199D01*
X380699Y313500D01*
Y312327D01*
X381299Y311727D01*
X386642D01*
X387691Y312776D01*
X425677D01*
X427200Y314299D01*
Y315626D01*
X428574Y317000D01*
X429701D01*
X431300Y318599D01*
Y319504D01*
X432396Y320600D01*
X441800D01*
X444035Y322835D01*
X444881D01*
G01X437008Y314961D02*
X435163Y313116D01*
Y310923D01*
X433445Y309205D01*
X432304D01*
X431108Y308009D01*
Y306868D01*
X429240Y305000D01*
X389279D01*
X386805Y307474D01*
X374268D01*
X373768Y306974D01*
Y305100D01*
X373268Y304600D01*
X372268D01*
X371768Y305100D01*
Y306974D01*
X371268Y307474D01*
X370268D01*
X369768Y306974D01*
Y305100D01*
X369268Y304600D01*
X368268D01*
X367768Y305100D01*
Y306974D01*
X367268Y307474D01*
X366268D01*
X365768Y306974D01*
Y305100D01*
X365268Y304600D01*
X364268D01*
X363768Y305100D01*
Y306974D01*
X363268Y307474D01*
X362268D01*
X361768Y306974D01*
Y305100D01*
X361268Y304600D01*
X360268D01*
X359768Y305100D01*
Y306974D01*
X359268Y307474D01*
X358268D01*
X357768Y306974D01*
Y305100D01*
X357268Y304600D01*
X356268D01*
X355768Y305100D01*
Y306974D01*
X355268Y307474D01*
X354268D01*
X353768Y306974D01*
Y305100D01*
X353268Y304600D01*
X352268D01*
X351768Y305100D01*
Y306974D01*
X351268Y307474D01*
X343343D01*
X342843Y306974D01*
Y305500D01*
X342343Y305000D01*
X341343D01*
X340843Y305500D01*
Y307479D01*
X336649Y311673D01*
X334639D01*
X329364Y316949D01*
G01X344000Y388500D02*
X352000D01*
X354519Y385981D01*
X468847D01*
X481413Y373415D01*
X482120D01*
X482829Y374123D01*
Y374829D01*
X473253Y384405D01*
Y385111D01*
X473963Y385819D01*
X474669D01*
X485101Y375387D01*
Y369418D01*
X483212Y367529D01*
Y361355D01*
X487350Y357217D01*
Y354520D01*
X491877Y349993D01*
Y338200D01*
X482200Y328523D01*
Y322099D01*
X480600Y320499D01*
Y315148D01*
X478511Y313059D01*
X475357D01*
X474357Y312059D01*
Y306257D01*
X473200Y305100D01*
X471100D01*
X470200Y304200D01*
Y302200D01*
X469300Y301300D01*
X467300D01*
X466400Y300400D01*
Y298100D01*
X465800Y297500D01*
X460201D01*
X458600Y295899D01*
Y294400D01*
X457299Y293099D01*
X456020D01*
X454261Y291340D01*
X452755D01*
G01X340375Y365944D02*
X340412Y365981D01*
X447067D01*
X458550Y354498D01*
Y336700D01*
X456450Y334600D01*
Y327400D01*
X456950Y326900D01*
X459800D01*
X460300Y327400D01*
Y333500D01*
G01X448818Y295276D02*
Y293581D01*
X449318Y293081D01*
X453103D01*
X454832Y294810D01*
Y296532D01*
X455700Y297400D01*
X457540D01*
X458800Y298660D01*
Y299952D01*
X459800Y300952D01*
X461180D01*
X461628Y301400D01*
X465400D01*
X466500Y302500D01*
Y304400D01*
X467400Y305300D01*
X469300D01*
X470645Y306645D01*
Y312037D01*
X471645Y313037D01*
X473800D01*
X474400Y313637D01*
Y315542D01*
X475828Y316970D01*
X477765D01*
X478500Y317705D01*
Y327900D01*
X489877Y339277D01*
Y349164D01*
X485350Y353691D01*
Y356388D01*
X481212Y360526D01*
Y368536D01*
X482628Y369952D01*
Y370660D01*
X481921Y371367D01*
X481213D01*
X479602Y369756D01*
X478894D01*
X478187Y370463D01*
Y371171D01*
X479131Y372115D01*
Y372823D01*
X478424Y373530D01*
X477716D01*
X476772Y372586D01*
X476064D01*
X475357Y373293D01*
Y374001D01*
X476301Y374945D01*
Y375653D01*
X475594Y376360D01*
X474886D01*
X473942Y375416D01*
X473234D01*
X472527Y376123D01*
Y376831D01*
X473471Y377775D01*
Y378483D01*
X472764Y379190D01*
X472056D01*
X471112Y378246D01*
X470404D01*
X469697Y378953D01*
Y379661D01*
X470641Y380605D01*
Y381313D01*
X469934Y382020D01*
X469226D01*
X468282Y381076D01*
X467574D01*
X466867Y381783D01*
Y382491D01*
X467356Y382981D01*
Y383481D01*
X466856Y383981D01*
X353191D01*
X351258Y385914D01*
X340747D01*
X340247Y386414D01*
Y388000D01*
X339747Y388500D01*
X338747D01*
X338247Y388000D01*
Y386414D01*
X337747Y385914D01*
X336568D01*
X336068Y386414D01*
Y388000D01*
X335568Y388500D01*
X334568D01*
X334068Y388000D01*
Y386414D01*
X333568Y385914D01*
X332386D01*
X331765Y386535D01*
G01X472442Y287402D02*
X473992Y285852D01*
X492952D01*
X493900Y286800D01*
Y288056D01*
X495400Y289556D01*
X500565D01*
X502387Y291378D01*
Y291982D01*
X504131Y293726D01*
X504580D01*
X505487Y294633D01*
Y295082D01*
X514025Y303620D01*
Y324990D01*
X517750Y328715D01*
Y332387D01*
X521665Y336302D01*
X553802D01*
X556800Y339300D01*
G01X464568Y287402D02*
X466266Y289100D01*
X473000D01*
X474828Y290928D01*
Y292500D01*
X476560Y294232D01*
Y298700D01*
X479160Y301300D01*
X480900D01*
X482336Y302736D01*
Y307364D01*
X484446Y309474D01*
X484895D01*
X485802Y310381D01*
Y311802D01*
X487500Y313500D01*
Y318950D01*
X490200Y321650D01*
Y323650D01*
X491250Y324700D01*
X492800D01*
X497000Y328900D01*
Y332771D01*
X500901Y336672D01*
Y342401D01*
X502138Y343638D01*
Y348500D01*
G01X510700Y367309D02*
X508600Y365209D01*
X505583D01*
X504350Y363976D01*
Y358042D01*
X509892Y352500D01*
X511796D01*
X511946Y352350D01*
X512905D01*
X515988Y349267D01*
Y345351D01*
X509250Y338613D01*
Y334500D01*
X504950Y330200D01*
Y324400D01*
X501753Y321203D01*
Y310585D01*
X499805Y308637D01*
X499356D01*
X498450Y307731D01*
Y307281D01*
X496639Y305470D01*
X496035D01*
X493800Y303235D01*
Y302631D01*
X492419Y301250D01*
X487050D01*
X486100Y300300D01*
Y298600D01*
X484400Y296900D01*
X483602D01*
X482702Y296000D01*
Y289789D01*
X480316Y287403D01*
G01X540200Y348300D02*
X538182Y346282D01*
X522990D01*
X513345Y336637D01*
Y332634D01*
X509680Y328969D01*
Y314574D01*
X507680Y312574D01*
X507231D01*
X506324Y311667D01*
Y311218D01*
X503743Y308637D01*
X503294D01*
X502145Y307488D01*
Y302947D01*
X500122Y300924D01*
X494924D01*
X493300Y299300D01*
X491800D01*
X490000Y297500D01*
X487892D01*
X486415Y296023D01*
Y293503D01*
X484252Y291340D01*
G01X550100Y348300D02*
Y341755D01*
X548595Y340250D01*
X522616D01*
X516345Y333979D01*
Y329976D01*
X512726Y326357D01*
Y310645D01*
X509781Y307700D01*
Y302864D01*
X504413Y297496D01*
X503964D01*
X502178Y295710D01*
Y295106D01*
X500547Y293475D01*
X495475D01*
X494200Y292200D01*
Y291200D01*
X492500Y289500D01*
X486350D01*
X484252Y287402D01*
G01X546100Y348300D02*
X542082Y344282D01*
X523819D01*
X514778Y335241D01*
Y331238D01*
X511186Y327646D01*
Y312143D01*
X508375Y309332D01*
X507926D01*
X506098Y307504D01*
Y303118D01*
X504057Y301077D01*
X503608D01*
X502347Y299816D01*
Y299212D01*
X500556Y297421D01*
X492078D01*
X489933Y295276D01*
X488189D01*
G01X506262Y348500D02*
Y344112D01*
X503250Y341100D01*
Y336192D01*
X499300Y332242D01*
Y328500D01*
X495500Y324700D01*
Y323500D01*
X493000Y321000D01*
X491800D01*
X489739Y318939D01*
Y310381D01*
X488832Y309474D01*
X488383D01*
X485802Y306893D01*
Y301902D01*
X485000Y301100D01*
X483000D01*
X482500Y300600D01*
Y298400D01*
X481600Y297500D01*
X479300D01*
X478000Y296200D01*
Y293500D01*
X480161Y291339D01*
X480315D01*
G01X489500Y371200D02*
X491850Y368850D01*
Y361950D01*
X491350Y361450D01*
Y356178D01*
X495877Y351651D01*
Y336653D01*
X485802Y326578D01*
Y314318D01*
X484895Y313411D01*
X484446D01*
X478367Y307332D01*
Y302946D01*
X477021Y301600D01*
X477017D01*
X474417Y299000D01*
Y294317D01*
X473100Y293000D01*
X469300D01*
X467639Y291339D01*
X460630D01*
G01X594400Y353000D02*
X589850D01*
X587651Y350801D01*
X530125D01*
X528576Y352350D01*
X517059D01*
X506200Y363209D01*
G01X506700Y367309D02*
X504854D01*
X502350Y364805D01*
Y357213D01*
X509063Y350500D01*
X510967D01*
X512138Y349329D01*
Y344330D01*
X507250Y339442D01*
Y335550D01*
X502950Y331250D01*
Y325450D01*
X497613Y320113D01*
Y310381D01*
X496706Y309474D01*
X496257D01*
X494513Y307730D01*
Y307281D01*
X492769Y305537D01*
X490576D01*
X488189Y303150D01*
G01X536200Y348300D02*
X522179D01*
X511345Y337466D01*
Y333495D01*
X507100Y329250D01*
Y323600D01*
X505500Y322000D01*
Y312587D01*
X503937Y311024D01*
G01X474200Y367500D02*
X477212Y364488D01*
Y358868D01*
X481350Y354730D01*
Y352033D01*
X483427Y349956D01*
Y338629D01*
X481298Y336500D01*
X478900D01*
X477900Y335500D01*
Y331912D01*
X475754Y329766D01*
Y324629D01*
X470714Y319589D01*
Y318016D01*
X469800Y317102D01*
X468002D01*
X462700Y311800D01*
Y308955D01*
X464567Y307088D01*
G01X492126Y307087D02*
X492397Y307358D01*
Y309102D01*
X493676Y310381D01*
Y318676D01*
X494513Y319513D01*
Y319541D01*
X495420Y320448D01*
X495448D01*
X497000Y322000D01*
Y322850D01*
X501150Y327000D01*
Y332200D01*
X505250Y336300D01*
Y340271D01*
X510138Y345159D01*
Y348500D01*
G01X488189Y322835D02*
Y325029D01*
X496000Y332840D01*
Y334600D01*
X498900Y337500D01*
Y345200D01*
X500000Y346300D01*
Y351300D01*
X496850Y354450D01*
Y359976D01*
X496901Y360027D01*
Y364846D01*
X497300Y365245D01*
Y377935D01*
X496300Y378935D01*
G01X510200Y363209D02*
X512350Y361059D01*
X514767D01*
X520976Y354850D01*
X529612D01*
X531161Y353301D01*
X585851D01*
X589550Y357000D01*
X594400D01*
G01X494400Y363800D02*
Y382700D01*
X503063Y391363D01*
X562658D01*
X562719Y391302D01*
X582664D01*
X589394Y384572D01*
G01X499100Y363409D02*
X499800Y364109D01*
Y383297D01*
X501100Y384597D01*
Y384600D01*
X505302Y388802D01*
X505305D01*
X505366Y388863D01*
X561622D01*
X561683Y388802D01*
X581560D01*
X588667Y381695D01*
Y378926D01*
X589391Y378202D01*
G01X457599Y419642D02*
X472557Y404684D01*
X602116D01*
X622100Y384700D01*
X644300D01*
X658700Y399100D01*
Y401701D01*
X658601Y401800D01*
G01X729921Y24410D02*
Y24716D01*
X726695Y27942D01*
Y52471D01*
X719766Y59400D01*
X702786D01*
X677546Y34160D01*
X653133D01*
X649278Y38015D01*
X633111D01*
X627603Y43523D01*
G01X751181Y34646D02*
X750469D01*
X747647Y37468D01*
Y56231D01*
X737668Y66210D01*
X700835D01*
X675425Y40800D01*
X667900D01*
G01X640144Y40969D02*
X641098Y40015D01*
X650107D01*
X653962Y36160D01*
X676717D01*
X702386Y61829D01*
X731510D01*
X739552Y53787D01*
Y29902D01*
X744094Y25360D01*
Y24410D01*
G01X700855Y426719D02*
X706770D01*
X713439Y420050D01*
X744919D01*
X749200Y415769D01*
Y311756D01*
X684962Y247518D01*
Y223524D01*
X676900Y215462D01*
Y208000D01*
X679527Y205373D01*
Y198424D01*
G01X704708Y260647D02*
X693110Y249049D01*
Y226478D01*
X690558Y223926D01*
Y205864D01*
X699980Y196442D01*
X715009D01*
X717567Y193884D01*
Y185754D01*
X718972Y184349D01*
Y180626D01*
X717751Y179405D01*
Y172414D01*
X718850Y171315D01*
X724756D01*
X731592Y164479D01*
Y156001D01*
X729921Y154330D01*
G01X658601Y401800D02*
X658800Y401999D01*
Y409959D01*
X675101Y426260D01*
X692850D01*
X695309Y428719D01*
X709632D01*
X716301Y422050D01*
X745748D01*
X752983Y414815D01*
Y307483D01*
X742700Y297200D01*
Y277600D01*
X714900Y249800D01*
X701046D01*
X695600Y244354D01*
G01X695375Y260875D02*
X746828Y312328D01*
Y415312D01*
X744090Y418050D01*
X702604D01*
X698738Y421916D01*
X676936D01*
X673900Y418880D01*
G01X751181Y29134D02*
X754663Y32616D01*
Y55393D01*
X759090Y59820D01*
X763560D01*
G01X720744Y92427D02*
X737746D01*
X738825Y91348D01*
X753326D01*
X755291Y93313D01*
X768362D01*
X780450Y105401D01*
Y130879D01*
X767429Y143900D01*
X756850D01*
X750800Y149950D01*
X742750D01*
X739030Y153670D01*
X730581D01*
X729921Y154330D01*
G01X793837Y275696D02*
X795687Y273846D01*
Y270994D01*
X794454Y269761D01*
X793155D01*
X791987Y268593D01*
Y260951D01*
X795702Y257236D01*
Y250319D01*
X793610Y248227D01*
Y244608D01*
X788687Y239685D01*
Y237037D01*
X771820Y220170D01*
X764068D01*
X753654Y209756D01*
Y189926D01*
X750865Y187137D01*
X750157D01*
X749217Y188077D01*
X748509D01*
X747802Y187370D01*
Y186662D01*
X748742Y185722D01*
Y185014D01*
X748035Y184307D01*
X747327D01*
X746387Y185247D01*
X745679D01*
X744972Y184540D01*
Y183832D01*
X745912Y182892D01*
Y182184D01*
X743292Y179564D01*
X742467D01*
X738352Y175449D01*
Y174615D01*
G01X793837Y271761D02*
X792326D01*
X789829Y269264D01*
Y259869D01*
X786837Y256877D01*
Y246742D01*
X782687Y242592D01*
Y240118D01*
X779437Y236868D01*
X778731D01*
X778073Y237525D01*
X777367D01*
X776658Y236816D01*
Y236110D01*
X777316Y235453D01*
Y234747D01*
X776607Y234038D01*
X775901D01*
X775243Y234695D01*
X774537D01*
X773828Y233986D01*
Y233280D01*
X774486Y232623D01*
Y231917D01*
X773777Y231208D01*
X773071D01*
X772413Y231865D01*
X771707D01*
X770998Y231156D01*
Y230450D01*
X771656Y229793D01*
Y229087D01*
X768843Y226274D01*
X756213D01*
X740489Y210550D01*
Y202686D01*
X735720Y197917D01*
Y178428D01*
X732670Y175378D01*
X732069D01*
X729920Y173229D01*
G01X736219Y170079D02*
X745360D01*
X746162Y170881D01*
Y171587D01*
X745445Y172304D01*
Y173012D01*
X746152Y173719D01*
X746860D01*
X747577Y173002D01*
X748283D01*
X748992Y173711D01*
Y174417D01*
X748046Y175363D01*
Y176071D01*
X748753Y176778D01*
X749461D01*
X750407Y175832D01*
X751113D01*
X757654Y182373D01*
Y204398D01*
X768810Y215554D01*
X774526D01*
X799702Y240730D01*
Y258894D01*
X797500Y261096D01*
Y264163D01*
X793837Y267826D01*
G01X733070Y170079D02*
X733783D01*
X735433Y171729D01*
X738232D01*
X741868Y175365D01*
X742936D01*
X748165Y180594D01*
X748871D01*
X750605Y178859D01*
X751311D01*
X752020Y179568D01*
Y180274D01*
X750286Y182009D01*
Y182715D01*
X750995Y183424D01*
X751701D01*
X753435Y181689D01*
X754141D01*
X754850Y182398D01*
Y183104D01*
X753116Y184839D01*
Y185545D01*
X755654Y188083D01*
Y207756D01*
X760248Y212350D01*
X761701D01*
X767066Y217715D01*
X773770D01*
X797702Y241647D01*
Y258065D01*
X795500Y260267D01*
Y262033D01*
X793837Y263696D01*
G01X729921Y179527D02*
X733565Y183171D01*
Y207808D01*
X735215Y209458D01*
Y214469D01*
X751088Y230342D01*
X764419D01*
X782837Y248760D01*
Y260568D01*
X784160Y261891D01*
X787171D01*
X787671Y262391D01*
Y275136D01*
X788171Y275636D01*
X789922D01*
X790422Y276136D01*
Y277136D01*
X789922Y277636D01*
X788296D01*
X787796Y278136D01*
Y279136D01*
X788296Y279636D01*
X793837D01*
G01X720471Y198424D02*
Y203773D01*
X723126Y206428D01*
Y219301D01*
X728088Y224263D01*
Y224971D01*
X726953Y226107D01*
Y226813D01*
X727661Y227521D01*
X728367D01*
X729503Y226386D01*
X730211D01*
X730918Y227093D01*
Y227801D01*
X729273Y229446D01*
Y230154D01*
X729980Y230861D01*
X730688D01*
X732333Y229216D01*
X733041D01*
X733748Y229923D01*
Y230631D01*
X732103Y232276D01*
Y232984D01*
X732810Y233691D01*
X733518D01*
X735163Y232046D01*
X735871D01*
X736578Y232753D01*
Y233461D01*
X734933Y235106D01*
Y235814D01*
X735640Y236521D01*
X736348D01*
X737993Y234876D01*
X738701D01*
X740305Y236480D01*
X752020D01*
X754641Y239101D01*
X764691D01*
X776837Y251247D01*
Y263826D01*
X780837Y267826D01*
G01X731915Y206310D02*
Y213998D01*
X732836Y214919D01*
Y215627D01*
X731667Y216795D01*
Y217501D01*
X732377Y218211D01*
X733083D01*
X734251Y217042D01*
X734959D01*
X735666Y217749D01*
Y218457D01*
X733331Y220792D01*
Y221500D01*
X734038Y222207D01*
X734746D01*
X737081Y219872D01*
X737789D01*
X738496Y220579D01*
Y221287D01*
X736161Y223622D01*
Y224330D01*
X736868Y225037D01*
X737576D01*
X739911Y222702D01*
X740619D01*
X741326Y223409D01*
Y224117D01*
X738991Y226452D01*
Y227160D01*
X739698Y227867D01*
X740406D01*
X742741Y225532D01*
X743449D01*
X746268Y228351D01*
Y229057D01*
X745275Y230051D01*
Y230757D01*
X745984Y231466D01*
X746690D01*
X747683Y230472D01*
X748389D01*
X750328Y232411D01*
X763659D01*
X780837Y249589D01*
Y261397D01*
X783331Y263891D01*
X784837D01*
G01X729920Y176378D02*
X732255D01*
X734720Y178843D01*
Y204295D01*
X737922Y207497D01*
Y210812D01*
X738585Y211475D01*
Y212183D01*
X737614Y213154D01*
Y213862D01*
X738321Y214569D01*
X739029D01*
X740000Y213598D01*
X740708D01*
X741415Y214305D01*
Y215013D01*
X740444Y215984D01*
Y216692D01*
X741151Y217399D01*
X741859D01*
X742830Y216428D01*
X743538D01*
X744245Y217135D01*
Y217843D01*
X743274Y218814D01*
Y219522D01*
X743981Y220229D01*
X744689D01*
X745660Y219258D01*
X746368D01*
X747075Y219965D01*
Y220673D01*
X746104Y221644D01*
Y222352D01*
X746811Y223059D01*
X747519D01*
X748490Y222088D01*
X749198D01*
X749905Y222795D01*
Y223503D01*
X748934Y224474D01*
Y225182D01*
X749641Y225889D01*
X750349D01*
X751320Y224918D01*
X752028D01*
X752735Y225625D01*
Y226333D01*
X752191Y226877D01*
Y227585D01*
X752898Y228292D01*
X753606D01*
X754150Y227748D01*
X754858D01*
X755384Y228274D01*
X765180D01*
X784837Y247931D01*
Y259951D01*
G01X738952Y184215D02*
X741585D01*
X742085Y184715D01*
Y186396D01*
X741585Y186896D01*
X739355D01*
X738855Y187396D01*
Y188396D01*
X739355Y188896D01*
X741585D01*
X742085Y189396D01*
Y209317D01*
X742654Y209886D01*
X743362D01*
X744923Y208325D01*
X745629D01*
X746339Y209033D01*
Y209739D01*
X744777Y211301D01*
Y212009D01*
X745484Y212716D01*
X746192D01*
X747967Y210941D01*
X748675D01*
X749382Y211648D01*
Y212356D01*
X747607Y214131D01*
Y214839D01*
X748314Y215546D01*
X749022D01*
X750994Y213574D01*
X751702D01*
X752409Y214281D01*
Y214989D01*
X750437Y216961D01*
Y217669D01*
X751144Y218376D01*
X751852D01*
X753824Y216404D01*
X754532D01*
X755239Y217111D01*
Y217819D01*
X753267Y219791D01*
Y220499D01*
X753974Y221206D01*
X754682D01*
X756654Y219234D01*
X757362D01*
X758069Y219941D01*
Y220649D01*
X756097Y222621D01*
Y223329D01*
X756972Y224204D01*
X769602D01*
X784687Y239289D01*
Y241343D01*
X789200Y245856D01*
Y255511D01*
X789700Y256011D01*
X793852D01*
G01X744052Y193784D02*
Y190755D01*
X744552Y190255D01*
X751154D01*
X751654Y190755D01*
Y191755D01*
X751154Y192255D01*
X748722D01*
X748222Y192755D01*
Y193755D01*
X748722Y194255D01*
X751154D01*
X751654Y194755D01*
Y195755D01*
X751154Y196255D01*
X748722D01*
X748222Y196755D01*
Y197755D01*
X748722Y198255D01*
X751154D01*
X751654Y198755D01*
Y199755D01*
X751154Y200255D01*
X747804D01*
X747304Y200755D01*
Y201755D01*
X747804Y202255D01*
X751154D01*
X751654Y202755D01*
Y203755D01*
X751154Y204255D01*
X744512D01*
X744012Y204755D01*
Y205755D01*
X744512Y206255D01*
X751154D01*
X751654Y206755D01*
Y210585D01*
X763273Y222204D01*
X770431D01*
X786687Y238460D01*
Y240514D01*
X791200Y245027D01*
Y251576D01*
X791700Y252076D01*
X793852D01*
G01X755693Y259540D02*
X753843Y257690D01*
X726349D01*
X704602Y235943D01*
Y219353D01*
X701574Y216325D01*
Y198424D01*
G01X711023Y198425D02*
Y201252D01*
X714817Y205046D01*
Y207523D01*
X717236Y209942D01*
Y212093D01*
X716736Y212593D01*
X715503D01*
X715003Y213093D01*
Y214093D01*
X715503Y214593D01*
X716441D01*
X716941Y215093D01*
Y216093D01*
X716441Y216593D01*
X715503D01*
X715003Y217093D01*
Y218093D01*
X715503Y218593D01*
X716525D01*
X717025Y219093D01*
Y222845D01*
X716525Y223345D01*
X715211D01*
X714711Y223845D01*
Y224845D01*
X715211Y225345D01*
X716736D01*
X717236Y225845D01*
Y228441D01*
X723991Y235196D01*
Y235904D01*
X723254Y236641D01*
Y237349D01*
X723961Y238056D01*
X724669D01*
X725406Y237319D01*
X726114D01*
X726821Y238026D01*
Y238734D01*
X726084Y239471D01*
Y240179D01*
X726791Y240886D01*
X727499D01*
X728236Y240149D01*
X728944D01*
X729696Y240901D01*
X750572D01*
X754548Y244877D01*
X759778D01*
X762545Y247644D01*
X766302D01*
X774657Y255999D01*
G01X704724Y198425D02*
Y199066D01*
X708602Y202944D01*
Y231242D01*
X726879Y249519D01*
X729813D01*
X730313Y250019D01*
Y251033D01*
X730813Y251533D01*
X731813D01*
X732313Y251033D01*
Y250019D01*
X732813Y249519D01*
X733813D01*
X734313Y250019D01*
Y251033D01*
X734813Y251533D01*
X735813D01*
X736313Y251033D01*
Y250019D01*
X736813Y249519D01*
X737813D01*
X738313Y250019D01*
Y251033D01*
X738813Y251533D01*
X739813D01*
X740313Y251033D01*
Y250019D01*
X740813Y249519D01*
X745012D01*
X745512Y250019D01*
Y251104D01*
X746012Y251604D01*
X747012D01*
X747512Y251104D01*
Y250019D01*
X748012Y249519D01*
X750014D01*
X751994Y251499D01*
X754411D01*
X760679Y257767D01*
X763506D01*
X765638Y255635D01*
G01X774637Y251876D02*
X765638Y242877D01*
X764810D01*
X764310Y243377D01*
Y244434D01*
X763810Y244934D01*
X762810D01*
X762310Y244434D01*
Y243377D01*
X761810Y242877D01*
X755377D01*
X751401Y238901D01*
X731822D01*
X728887Y235966D01*
Y234769D01*
X725445Y231327D01*
X724737D01*
X724216Y231848D01*
X723508D01*
X722801Y231141D01*
Y230433D01*
X725020Y228214D01*
Y227506D01*
X724313Y226799D01*
X723605D01*
X721386Y229018D01*
X720678D01*
X719971Y228311D01*
Y227582D01*
X721597Y225956D01*
Y225166D01*
X719046Y222615D01*
Y218967D01*
X719546Y218467D01*
X720422D01*
X720922Y217967D01*
Y216967D01*
X720422Y216467D01*
X719546D01*
X719046Y215967D01*
Y214967D01*
X719546Y214467D01*
X720422D01*
X720922Y213967D01*
Y212967D01*
X720422Y212467D01*
X719546D01*
X719046Y211967D01*
Y208721D01*
X716680Y206355D01*
Y203995D01*
X717322Y203353D01*
Y198425D01*
G01X784837Y271761D02*
X782837Y269761D01*
X774026D01*
X772637Y268372D01*
Y256976D01*
X765392Y249731D01*
X758564D01*
X755923Y247090D01*
X753732D01*
X749582Y242940D01*
X725958D01*
X721219Y238201D01*
Y236824D01*
X712602Y228207D01*
Y216435D01*
X713310Y215727D01*
Y206016D01*
X707873Y200579D01*
Y198424D01*
G01X784837Y267826D02*
X784437D01*
X778837Y262226D01*
Y250418D01*
X762899Y234480D01*
X762164D01*
X761664Y234980D01*
Y236538D01*
X761164Y237038D01*
X760164D01*
X759664Y236538D01*
Y234980D01*
X759164Y234480D01*
X758164D01*
X757664Y234980D01*
Y236538D01*
X757164Y237038D01*
X756164D01*
X755664Y236538D01*
Y234980D01*
X755164Y234480D01*
X743390D01*
X728725Y219815D01*
X726933D01*
X726433Y219315D01*
Y218315D01*
X726933Y217815D01*
X729008D01*
X729508Y217315D01*
Y216315D01*
X729008Y215815D01*
X726933D01*
X726433Y215315D01*
Y214315D01*
X726933Y213815D01*
X728800D01*
X729300Y213315D01*
Y212315D01*
X728800Y211815D01*
X726933D01*
X726433Y211315D01*
Y204589D01*
X725933Y204089D01*
X723943D01*
X723443Y203589D01*
Y202589D01*
X723943Y202089D01*
X725933D01*
X726433Y201589D01*
Y198924D01*
X725933Y198424D01*
X723621D01*
G01X793837Y287696D02*
X793457D01*
X781344Y275583D01*
X773028D01*
X759415Y261970D01*
Y260433D01*
X752627Y253645D01*
X728176D01*
X706602Y232071D01*
Y218524D01*
X705336Y217258D01*
Y208437D01*
G01X780837Y271761D02*
X772035D01*
X768787Y268513D01*
Y255955D01*
X766263Y253431D01*
X759257D01*
X754969Y249143D01*
X752772D01*
X748883Y245254D01*
X725443D01*
X710602Y230413D01*
Y214725D01*
X711310Y214017D01*
Y207023D01*
G01X753560Y273780D02*
X771116Y291336D01*
Y345648D01*
X775672Y350204D01*
G01X767890Y273380D02*
Y284574D01*
X773616Y290300D01*
Y335511D01*
X776497Y338392D01*
G54D18*
G01X121778Y-377522D02*
X122652Y-376647D01*
X123307Y-375189D01*
X123744Y-373146D01*
X123307Y-371397D01*
X122434Y-370230D01*
X120905Y-369355D01*
X115010D01*
Y-386855D01*
X122215D01*
X123744Y-385689D01*
X124617Y-383938D01*
X125054Y-381897D01*
X124617Y-379855D01*
X123307Y-378105D01*
X121778Y-377522D01*
X115010D01*
G01X134475Y-386855D02*
Y-375189D01*
G01Y-377522D02*
X135567Y-376355D01*
X136659Y-375480D01*
X138187Y-375189D01*
X139278Y-375480D01*
X140589Y-376355D01*
G01X150447Y-392105D02*
X151757Y-392688D01*
X153504Y-392105D01*
X154595Y-390939D01*
X155469Y-389480D01*
X156778Y-384814D01*
X159617Y-375189D01*
G01X152630D02*
X156778Y-384814D01*
G01X176025Y-376647D02*
X174497Y-375480D01*
X173187Y-375189D01*
X171440Y-375772D01*
X170130Y-376938D01*
X169257Y-378980D01*
X169038Y-381022D01*
X169257Y-383064D01*
X170130Y-384814D01*
X171440Y-386272D01*
X173187Y-386855D01*
X174715Y-386272D01*
X176025Y-385105D01*
G01X186757Y-378980D02*
X193744D01*
X193089Y-376938D01*
X191997Y-375772D01*
X190469Y-375189D01*
X188940Y-375480D01*
X187630Y-376355D01*
X186757Y-378397D01*
X186320Y-380147D01*
Y-381897D01*
X186757Y-383647D01*
X187849Y-385397D01*
X189159Y-386563D01*
X190687Y-386855D01*
X192215Y-386272D01*
X193744Y-384522D01*
G01X229835Y-370814D02*
X228525Y-369938D01*
X226997Y-369355D01*
X225250D01*
X223285Y-370230D01*
X221757Y-371688D01*
X220665Y-373439D01*
X219792Y-376355D01*
X219573Y-378980D01*
X220010Y-381605D01*
X220665Y-383355D01*
X221975Y-385105D01*
X223504Y-386272D01*
X225032Y-386855D01*
X226560D01*
X228089Y-386272D01*
X229399Y-385397D01*
X230491Y-384231D01*
G01X246462Y-386855D02*
Y-375189D01*
G01Y-377230D02*
X245589Y-376064D01*
X244278Y-375480D01*
X242750Y-375189D01*
X241222Y-375772D01*
X239912Y-376938D01*
X239038Y-378688D01*
X238602Y-381022D01*
X239038Y-383355D01*
X239912Y-385105D01*
X241222Y-386272D01*
X242750Y-386855D01*
X244278Y-386563D01*
X245589Y-385689D01*
X246462Y-384522D01*
G01X256320Y-386855D02*
Y-375189D01*
G01Y-378105D02*
X257194Y-376647D01*
X258504Y-375480D01*
X260250Y-375189D01*
X261778Y-375480D01*
X263089Y-376647D01*
X263744Y-378688D01*
Y-386855D01*
G01X272947Y-392105D02*
X274257Y-392688D01*
X276004Y-392105D01*
X277095Y-390939D01*
X277969Y-389480D01*
X279278Y-384814D01*
X282117Y-375189D01*
G01X275130D02*
X279278Y-384814D01*
G01X295032Y-386855D02*
X293722Y-386563D01*
X292412Y-385397D01*
X291538Y-383355D01*
X291102Y-381022D01*
X291538Y-378688D01*
X292412Y-376647D01*
X293722Y-375480D01*
X295032Y-375189D01*
X296342Y-375480D01*
X297652Y-376647D01*
X298525Y-378688D01*
X298744Y-381022D01*
X298525Y-383355D01*
X297652Y-385397D01*
X296342Y-386563D01*
X295032Y-386855D01*
G01X308820D02*
Y-375189D01*
G01Y-378105D02*
X309694Y-376647D01*
X311004Y-375480D01*
X312750Y-375189D01*
X314278Y-375480D01*
X315589Y-376647D01*
X316244Y-378688D01*
Y-386855D01*
G01X342947Y-384522D02*
X344694Y-385980D01*
X346659Y-386855D01*
X348405D01*
X350152Y-385980D01*
X351462Y-384522D01*
X352117Y-382480D01*
X351680Y-380439D01*
X350589Y-378688D01*
X348624Y-377522D01*
X346004Y-376938D01*
X344475Y-375772D01*
X343820Y-373730D01*
X344257Y-371688D01*
X345349Y-370230D01*
X346877Y-369355D01*
X348405D01*
X349934Y-369938D01*
X351244Y-371397D01*
G01X369835Y-370814D02*
X368525Y-369938D01*
X366997Y-369355D01*
X365250D01*
X363285Y-370230D01*
X361757Y-371688D01*
X360665Y-373439D01*
X359792Y-376355D01*
X359573Y-378980D01*
X360010Y-381605D01*
X360665Y-383355D01*
X361975Y-385105D01*
X363504Y-386272D01*
X365032Y-386855D01*
X366560D01*
X368089Y-386272D01*
X369399Y-385397D01*
X370491Y-384231D01*
G01X387335Y-370814D02*
X386025Y-369938D01*
X384497Y-369355D01*
X382750D01*
X380785Y-370230D01*
X379257Y-371688D01*
X378165Y-373439D01*
X377292Y-376355D01*
X377073Y-378980D01*
X377510Y-381605D01*
X378165Y-383355D01*
X379475Y-385105D01*
X381004Y-386272D01*
X382532Y-386855D01*
X384060D01*
X385589Y-386272D01*
X386899Y-385397D01*
X387991Y-384231D01*
G01X210605Y-341855D02*
Y-324355D01*
X216282Y-338938D01*
X221959Y-324355D01*
Y-341855D01*
G01X233782D02*
X232472Y-341563D01*
X231162Y-340397D01*
X230288Y-338355D01*
X229852Y-336022D01*
X230288Y-333688D01*
X231162Y-331647D01*
X232472Y-330480D01*
X233782Y-330189D01*
X235092Y-330480D01*
X236402Y-331647D01*
X237275Y-333688D01*
X237494Y-336022D01*
X237275Y-338355D01*
X236402Y-340397D01*
X235092Y-341563D01*
X233782Y-341855D01*
G01X255212Y-324355D02*
Y-341855D01*
G01Y-339231D02*
X254339Y-340689D01*
X253028Y-341563D01*
X251500Y-341855D01*
X249754Y-341272D01*
X248444Y-339814D01*
X247570Y-338064D01*
X247352Y-336022D01*
X247570Y-333980D01*
X248444Y-332230D01*
X249754Y-330772D01*
X251500Y-330189D01*
X253028Y-330480D01*
X254120Y-331064D01*
X255212Y-332230D01*
G01X265507Y-333980D02*
X272494D01*
X271839Y-331938D01*
X270747Y-330772D01*
X269219Y-330189D01*
X267690Y-330480D01*
X266380Y-331355D01*
X265507Y-333397D01*
X265070Y-335147D01*
Y-336897D01*
X265507Y-338647D01*
X266599Y-340397D01*
X267909Y-341563D01*
X269437Y-341855D01*
X270965Y-341272D01*
X272494Y-339522D01*
G01X286282Y-341855D02*
Y-324355D01*
G01X566882Y-386855D02*
Y-369355D01*
X564262Y-372855D01*
G01Y-386855D02*
X569502D01*
G01X580234Y-379564D02*
X581762Y-377522D01*
X583072Y-376355D01*
X584819Y-375772D01*
X586347Y-376355D01*
X587439Y-377522D01*
X588312Y-379272D01*
X588530Y-381313D01*
X588312Y-383064D01*
X587439Y-384814D01*
X586128Y-386272D01*
X584600Y-386855D01*
X582854Y-386272D01*
X581325Y-384522D01*
X580452Y-381897D01*
X580234Y-378980D01*
X580670Y-375189D01*
X581325Y-373146D01*
X582417Y-371105D01*
X583945Y-369647D01*
X585474Y-369355D01*
X587002Y-369938D01*
X588094Y-371397D01*
G01X597079Y-383355D02*
X598388Y-385397D01*
X600135Y-386563D01*
X602100Y-386855D01*
X603847Y-386563D01*
X605594Y-385105D01*
X606685Y-383355D01*
X606904Y-381605D01*
X606467Y-379564D01*
X604939Y-378105D01*
X603410Y-377522D01*
X601445D01*
G01X603410D02*
X604720Y-376647D01*
X605812Y-375189D01*
X606249Y-373439D01*
X605812Y-371688D01*
X604720Y-370230D01*
X602755Y-369355D01*
X600790Y-369647D01*
X598825Y-370814D01*
G01X619382Y-386855D02*
Y-369355D01*
X616762Y-372855D01*
G01Y-386855D02*
X622002D01*
G01X632734Y-379564D02*
X634262Y-377522D01*
X635572Y-376355D01*
X637319Y-375772D01*
X638847Y-376355D01*
X639939Y-377522D01*
X640812Y-379272D01*
X641030Y-381313D01*
X640812Y-383064D01*
X639939Y-384814D01*
X638628Y-386272D01*
X637100Y-386855D01*
X635354Y-386272D01*
X633825Y-384522D01*
X632952Y-381897D01*
X632734Y-378980D01*
X633170Y-375189D01*
X633825Y-373146D01*
X634917Y-371105D01*
X636445Y-369647D01*
X637974Y-369355D01*
X639502Y-369938D01*
X640594Y-371397D01*
G01X553765Y-341855D02*
Y-324355D01*
X559005D01*
X560752Y-325230D01*
X562062Y-327272D01*
X562499Y-329605D01*
X562062Y-331938D01*
X560970Y-333688D01*
X559005Y-334564D01*
X553765D01*
G01X580435Y-325814D02*
X579125Y-324938D01*
X577597Y-324355D01*
X575850D01*
X573885Y-325230D01*
X572357Y-326688D01*
X571265Y-328439D01*
X570392Y-331355D01*
X570173Y-333980D01*
X570610Y-336605D01*
X571265Y-338355D01*
X572575Y-340105D01*
X574104Y-341272D01*
X575632Y-341855D01*
X577160D01*
X578689Y-341272D01*
X579999Y-340397D01*
X581091Y-339231D01*
G01X594878Y-332522D02*
X595752Y-331647D01*
X596407Y-330189D01*
X596844Y-328146D01*
X596407Y-326397D01*
X595534Y-325230D01*
X594005Y-324355D01*
X588110D01*
Y-341855D01*
X595315D01*
X596844Y-340689D01*
X597717Y-338938D01*
X598154Y-336897D01*
X597717Y-334855D01*
X596407Y-333105D01*
X594878Y-332522D01*
X588110D01*
G01X604082Y-347688D02*
X617182D01*
G01X623110Y-341855D02*
Y-324355D01*
X633154Y-341855D01*
Y-324355D01*
G01X645632Y-341855D02*
X643885Y-341563D01*
X642357Y-340397D01*
X641047Y-338647D01*
X640173Y-336605D01*
X639737Y-334272D01*
Y-331938D01*
X640173Y-329605D01*
X641047Y-327563D01*
X642357Y-325814D01*
X643885Y-324647D01*
X645632Y-324355D01*
X647378Y-324647D01*
X648907Y-325814D01*
X650217Y-327563D01*
X651091Y-329605D01*
X651527Y-331938D01*
Y-334272D01*
X651091Y-336605D01*
X650217Y-338647D01*
X648907Y-340397D01*
X647378Y-341563D01*
X645632Y-341855D01*
G01X696473Y-324355D02*
X701932Y-341855D01*
X707391Y-324355D01*
G01X723799Y-341855D02*
X715065D01*
Y-324355D01*
X723799D01*
G01X720305Y-332813D02*
X715065D01*
G01X732565Y-341855D02*
Y-324355D01*
X738024D01*
X739770Y-325230D01*
X740862Y-326397D01*
X741299Y-328730D01*
X740862Y-331064D01*
X739552Y-332522D01*
X738024Y-333397D01*
X732565D01*
G01X738024D02*
X741299Y-341855D01*
G01X754432Y-342438D02*
X753995Y-342147D01*
Y-341563D01*
X754432Y-341272D01*
X754869Y-341563D01*
Y-342147D01*
X754432Y-342438D01*
G01X728182Y-386855D02*
Y-369355D01*
X725562Y-372855D01*
G01Y-386855D02*
X730802D01*
G01X856265Y-369355D02*
Y-386855D01*
X864999D01*
G01X873329Y-383355D02*
X874638Y-385397D01*
X876385Y-386563D01*
X878350Y-386855D01*
X880097Y-386563D01*
X881844Y-385105D01*
X882935Y-383355D01*
X883154Y-381605D01*
X882717Y-379564D01*
X881189Y-378105D01*
X879660Y-377522D01*
X877695D01*
G01X879660D02*
X880970Y-376647D01*
X882062Y-375189D01*
X882499Y-373439D01*
X882062Y-371688D01*
X880970Y-370230D01*
X879005Y-369355D01*
X877040Y-369647D01*
X875075Y-370814D01*
G01X830015Y-324355D02*
Y-341855D01*
X838749D01*
G01X855812D02*
Y-330189D01*
G01Y-332230D02*
X854939Y-331064D01*
X853628Y-330480D01*
X852100Y-330189D01*
X850572Y-330772D01*
X849262Y-331938D01*
X848388Y-333688D01*
X847952Y-336022D01*
X848388Y-338355D01*
X849262Y-340105D01*
X850572Y-341272D01*
X852100Y-341855D01*
X853628Y-341563D01*
X854939Y-340689D01*
X855812Y-339522D01*
G01X864797Y-347105D02*
X866107Y-347688D01*
X867854Y-347105D01*
X868945Y-345939D01*
X869819Y-344480D01*
X871128Y-339814D01*
X873967Y-330189D01*
G01X866980D02*
X871128Y-339814D01*
G01X883607Y-333980D02*
X890594D01*
X889939Y-331938D01*
X888847Y-330772D01*
X887319Y-330189D01*
X885790Y-330480D01*
X884480Y-331355D01*
X883607Y-333397D01*
X883170Y-335147D01*
Y-336897D01*
X883607Y-338647D01*
X884699Y-340397D01*
X886009Y-341563D01*
X887537Y-341855D01*
X889065Y-341272D01*
X890594Y-339522D01*
G01X901325Y-341855D02*
Y-330189D01*
G01Y-332522D02*
X902417Y-331355D01*
X903509Y-330480D01*
X905037Y-330189D01*
X906128Y-330480D01*
X907439Y-331355D01*
G01X994432Y-386855D02*
X992685Y-386563D01*
X991157Y-385397D01*
X989847Y-383647D01*
X988973Y-381605D01*
X988537Y-379272D01*
Y-376938D01*
X988973Y-374605D01*
X989847Y-372563D01*
X991157Y-370814D01*
X992685Y-369647D01*
X994432Y-369355D01*
X996178Y-369647D01*
X997707Y-370814D01*
X999017Y-372563D01*
X999891Y-374605D01*
X1000327Y-376938D01*
Y-379272D01*
X999891Y-381605D01*
X999017Y-383647D01*
X997707Y-385397D01*
X996178Y-386563D01*
X994432Y-386855D01*
G01X996178Y-382188D02*
X998799Y-386855D01*
G01X1007129Y-369355D02*
Y-381897D01*
X1008002Y-384522D01*
X1009749Y-386272D01*
X1011932Y-386855D01*
X1014115Y-386272D01*
X1015862Y-384522D01*
X1016735Y-381897D01*
Y-369355D01*
G01X1026812D02*
X1032052D01*
G01X1029432D02*
Y-386855D01*
G01X1026812D02*
X1032052D01*
G01X1041910D02*
Y-369355D01*
X1051954Y-386855D01*
Y-369355D01*
G01X1069235Y-370814D02*
X1067925Y-369938D01*
X1066397Y-369355D01*
X1064650D01*
X1062685Y-370230D01*
X1061157Y-371688D01*
X1060065Y-373439D01*
X1059192Y-376355D01*
X1058973Y-378980D01*
X1059410Y-381605D01*
X1060065Y-383355D01*
X1061375Y-385105D01*
X1062904Y-386272D01*
X1064432Y-386855D01*
X1065960D01*
X1067489Y-386272D01*
X1068799Y-385397D01*
X1069891Y-384231D01*
G01X1081932Y-386855D02*
Y-378980D01*
X1077565Y-369355D01*
G01X1086299D02*
X1081932Y-378980D01*
G01X972129Y-341855D02*
Y-324355D01*
X976495D01*
X978242Y-325230D01*
X979552Y-326397D01*
X980644Y-328146D01*
X981517Y-330189D01*
X981735Y-333105D01*
X981517Y-336022D01*
X980644Y-338064D01*
X979552Y-339814D01*
X978242Y-340980D01*
X976495Y-341855D01*
X972129D01*
G01X991157Y-333980D02*
X998144D01*
X997489Y-331938D01*
X996397Y-330772D01*
X994869Y-330189D01*
X993340Y-330480D01*
X992030Y-331355D01*
X991157Y-333397D01*
X990720Y-335147D01*
Y-336897D01*
X991157Y-338647D01*
X992249Y-340397D01*
X993559Y-341563D01*
X995087Y-341855D01*
X996615Y-341272D01*
X998144Y-339522D01*
G01X1008657Y-339814D02*
X1009749Y-340980D01*
X1011277Y-341855D01*
X1012587D01*
X1013897Y-341272D01*
X1014770Y-340397D01*
X1015207Y-339231D01*
X1014989Y-337480D01*
X1014115Y-336605D01*
X1010185Y-334855D01*
X1009312Y-332813D01*
X1009749Y-331355D01*
X1010622Y-330480D01*
X1011932Y-330189D01*
X1013242Y-330480D01*
X1014552Y-331355D01*
G01X1029432Y-330189D02*
Y-341855D01*
G01Y-325522D02*
X1028995Y-325230D01*
Y-324647D01*
X1029432Y-324355D01*
X1029869Y-324647D01*
Y-325230D01*
X1029432Y-325522D01*
G01X1043875Y-346230D02*
X1045404Y-347397D01*
X1047150Y-347688D01*
X1048678Y-347397D01*
X1049989Y-345939D01*
X1050862Y-343897D01*
Y-330189D01*
G01Y-332522D02*
X1049989Y-331355D01*
X1048678Y-330480D01*
X1047150Y-330189D01*
X1045404Y-330772D01*
X1044312Y-331938D01*
X1043438Y-333980D01*
X1043002Y-336022D01*
X1043220Y-337772D01*
X1044094Y-339814D01*
X1045404Y-341272D01*
X1047150Y-341855D01*
X1048460Y-341563D01*
X1049989Y-340397D01*
X1050862Y-339231D01*
G01X1060720Y-341855D02*
Y-330189D01*
G01Y-333105D02*
X1061594Y-331647D01*
X1062904Y-330480D01*
X1064650Y-330189D01*
X1066178Y-330480D01*
X1067489Y-331647D01*
X1068144Y-333688D01*
Y-341855D01*
G01X1078657Y-333980D02*
X1085644D01*
X1084989Y-331938D01*
X1083897Y-330772D01*
X1082369Y-330189D01*
X1080840Y-330480D01*
X1079530Y-331355D01*
X1078657Y-333397D01*
X1078220Y-335147D01*
Y-336897D01*
X1078657Y-338647D01*
X1079749Y-340397D01*
X1081059Y-341563D01*
X1082587Y-341855D01*
X1084115Y-341272D01*
X1085644Y-339522D01*
G01X1096375Y-341855D02*
Y-330189D01*
G01Y-332522D02*
X1097467Y-331355D01*
X1098559Y-330480D01*
X1100087Y-330189D01*
X1101178Y-330480D01*
X1102489Y-331355D01*
G01X1143132Y-369355D02*
X1141385Y-369938D01*
X1140075Y-371397D01*
X1139202Y-373146D01*
X1138547Y-375480D01*
X1138329Y-378105D01*
X1138547Y-380730D01*
X1139202Y-383064D01*
X1140075Y-384814D01*
X1141385Y-386272D01*
X1143132Y-386855D01*
X1144878Y-386272D01*
X1146189Y-384814D01*
X1147062Y-383064D01*
X1147717Y-380730D01*
X1147935Y-378105D01*
X1147717Y-375480D01*
X1147062Y-373146D01*
X1146189Y-371397D01*
X1144878Y-369938D01*
X1143132Y-369355D01*
G01X1156484Y-379564D02*
X1158012Y-377522D01*
X1159322Y-376355D01*
X1161069Y-375772D01*
X1162597Y-376355D01*
X1163689Y-377522D01*
X1164562Y-379272D01*
X1164780Y-381313D01*
X1164562Y-383064D01*
X1163689Y-384814D01*
X1162378Y-386272D01*
X1160850Y-386855D01*
X1159104Y-386272D01*
X1157575Y-384522D01*
X1156702Y-381897D01*
X1156484Y-378980D01*
X1156920Y-375189D01*
X1157575Y-373146D01*
X1158667Y-371105D01*
X1160195Y-369647D01*
X1161724Y-369355D01*
X1163252Y-369938D01*
X1164344Y-371397D01*
G01X1174202Y-387438D02*
X1182062Y-369355D01*
G01X1191484Y-372272D02*
X1192794Y-370522D01*
X1194322Y-369647D01*
X1196069Y-369355D01*
X1198252Y-369938D01*
X1199780Y-371397D01*
X1200217Y-373146D01*
X1199999Y-374897D01*
X1199125Y-376355D01*
X1194759Y-379272D01*
X1192794Y-381313D01*
X1191484Y-384231D01*
X1191047Y-386855D01*
X1200217D01*
G01X1213132D02*
Y-369355D01*
X1210512Y-372855D01*
G01Y-386855D02*
X1215752D01*
G01X1226702Y-387438D02*
X1234562Y-369355D01*
G01X1243984Y-372272D02*
X1245294Y-370522D01*
X1246822Y-369647D01*
X1248569Y-369355D01*
X1250752Y-369938D01*
X1252280Y-371397D01*
X1252717Y-373146D01*
X1252499Y-374897D01*
X1251625Y-376355D01*
X1247259Y-379272D01*
X1245294Y-381313D01*
X1243984Y-384231D01*
X1243547Y-386855D01*
X1252717D01*
G01X1265632Y-369355D02*
X1263885Y-369938D01*
X1262575Y-371397D01*
X1261702Y-373146D01*
X1261047Y-375480D01*
X1260829Y-378105D01*
X1261047Y-380730D01*
X1261702Y-383064D01*
X1262575Y-384814D01*
X1263885Y-386272D01*
X1265632Y-386855D01*
X1267378Y-386272D01*
X1268689Y-384814D01*
X1269562Y-383064D01*
X1270217Y-380730D01*
X1270435Y-378105D01*
X1270217Y-375480D01*
X1269562Y-373146D01*
X1268689Y-371397D01*
X1267378Y-369938D01*
X1265632Y-369355D01*
G01X1283132Y-386855D02*
Y-369355D01*
X1280512Y-372855D01*
G01Y-386855D02*
X1285752D01*
G01X1300195D02*
X1300632Y-383064D01*
X1301287Y-379855D01*
X1302160Y-376938D01*
X1303252Y-373730D01*
X1304999Y-369355D01*
X1296265D01*
G01X1190829Y-341855D02*
Y-324355D01*
X1195195D01*
X1196942Y-325230D01*
X1198252Y-326397D01*
X1199344Y-328146D01*
X1200217Y-330189D01*
X1200435Y-333105D01*
X1200217Y-336022D01*
X1199344Y-338064D01*
X1198252Y-339814D01*
X1196942Y-340980D01*
X1195195Y-341855D01*
X1190829D01*
G01X1217062D02*
Y-330189D01*
G01Y-332230D02*
X1216189Y-331064D01*
X1214878Y-330480D01*
X1213350Y-330189D01*
X1211822Y-330772D01*
X1210512Y-331938D01*
X1209638Y-333688D01*
X1209202Y-336022D01*
X1209638Y-338355D01*
X1210512Y-340105D01*
X1211822Y-341272D01*
X1213350Y-341855D01*
X1214878Y-341563D01*
X1216189Y-340689D01*
X1217062Y-339522D01*
G01X1230632Y-324355D02*
Y-341855D01*
G01X1227575Y-330189D02*
X1233689D01*
G01X1244857Y-333980D02*
X1251844D01*
X1251189Y-331938D01*
X1250097Y-330772D01*
X1248569Y-330189D01*
X1247040Y-330480D01*
X1245730Y-331355D01*
X1244857Y-333397D01*
X1244420Y-335147D01*
Y-336897D01*
X1244857Y-338647D01*
X1245949Y-340397D01*
X1247259Y-341563D01*
X1248787Y-341855D01*
X1250315Y-341272D01*
X1251844Y-339522D01*
G54D19*
G01X501368Y199667D02*
Y199754D01*
X501593Y199979D01*
Y208312D01*
G03X501243Y208662I-350J0D01*
G01X500000D01*
G01X502568Y199667D02*
Y199754D01*
X502343Y199979D01*
Y208312D01*
G02X502693Y208662I350J0D01*
G01X503937D01*
G01X496063Y212599D02*
X497306D01*
G02X497656Y212249I0J-350D01*
G01Y211551D01*
G03X498034Y210636I1294J-1D01*
G03X498949Y210258I914J916D01*
G01X504679D01*
X505540Y209397D01*
Y199487D01*
X505315Y199262D01*
Y199175D01*
G01X500000Y212599D02*
X498756D01*
G03X498406Y212249I0J-350D01*
G01Y211551D01*
G03X498565Y211167I543J0D01*
G03X498949Y211008I384J384D01*
G01X504990D01*
X506290Y209708D01*
Y199487D01*
X506515Y199262D01*
Y199175D01*
G01X509250Y199711D02*
Y199798D01*
X509475Y200023D01*
Y213140D01*
X508422Y214193D01*
X498941D01*
G02X498032Y214568I-2J1285D01*
G01X498030Y214570D01*
G02X497656Y215476I910J906D01*
G01Y216186D01*
G03X497306Y216536I-350J0D01*
G01X496063D01*
G01X510450Y199711D02*
Y199798D01*
X510225Y200023D01*
Y213451D01*
X508733Y214943D01*
X498940D01*
G02X498562Y215099I0J535D01*
G01X498561Y215100D01*
G02X498406Y215476I379J376D01*
G01Y216186D01*
G02X498756Y216536I350J0D01*
G01X500000D01*
G01X513600Y211838D02*
Y211925D01*
X513825Y212150D01*
Y215800D01*
X511502Y218123D01*
X499254D01*
G02X498123Y218592I0J1598D01*
G02X497656Y219721I1131J1129D01*
G01Y220123D01*
G03X497306Y220473I-350J0D01*
G01X496063D01*
G01X514800Y211838D02*
Y211925D01*
X514575Y212150D01*
Y216111D01*
X511813Y218873D01*
X499254D01*
G02X498654Y219122I0J847D01*
G02X498406Y219721I599J599D01*
G01Y220123D01*
G02X498756Y220473I350J0D01*
G01X500000D01*
G01X496063Y224410D02*
X497306D01*
G02X497656Y224060I0J-350D01*
G01Y223235D01*
G03X498001Y222405I1175J2D01*
G01X498020Y222385D01*
G03X498801Y222061I780J777D01*
G01X508738D01*
X508963Y221836D01*
X509050D01*
G01X500000Y224410D02*
X498756D01*
G03X498406Y224060I0J-350D01*
G01Y223236D01*
G03X498531Y222936I425J1D01*
G01X498552Y222915D01*
G03X498801Y222811I249J246D01*
G01X508738D01*
X508963Y223036D01*
X509050D01*
G01X496063Y228347D02*
X497306D01*
G02X497656Y227997I0J-350D01*
G01Y227317D01*
G03X498039Y226393I1306J0D01*
G03X498960Y226012I921J923D01*
G01X513441D01*
X515757Y228328D01*
X518176D01*
X518401Y228103D01*
X518488D01*
G01X500000Y228347D02*
X498756D01*
G03X498406Y227997I0J-350D01*
G01Y227317D01*
G03X498569Y226924I555J0D01*
G03X498960Y226762I391J391D01*
G01X513130D01*
X515446Y229078D01*
X518176D01*
X518401Y229303D01*
X518488D01*
G01X496063Y232284D02*
X497306D01*
G02X497656Y231934I0J-350D01*
G01Y231118D01*
G03X498000Y230285I1178J-1D01*
G03X498833Y229941I832J834D01*
G01X513383D01*
X514966Y231524D01*
X518160D01*
X518385Y231299D01*
X518472D01*
G01X500000Y232284D02*
X498756D01*
G03X498406Y231934I0J-350D01*
G01Y231118D01*
G03X498531Y230816I427J0D01*
G03X498833Y230691I302J302D01*
G01X513072D01*
X514655Y232274D01*
X518160D01*
X518385Y232499D01*
X518472D01*
G01X496063Y236221D02*
X497306D01*
G02X497656Y235871I0J-350D01*
G01Y234983D01*
G03X497979Y234201I1105J-1D01*
G03X498761Y233878I781J782D01*
G01X510171D01*
X510396Y233653D01*
X510483D01*
G01X500000Y236221D02*
X498756D01*
G03X498406Y235871I0J-350D01*
G01Y234983D01*
G03X498510Y234732I355J0D01*
G03X498761Y234628I251J251D01*
G01X510171D01*
X510396Y234853D01*
X510483D01*
G01X657479Y116536D02*
X655903Y114960D01*
X651283D01*
X651058Y114735D01*
X650971D01*
G01Y115935D02*
X651058D01*
X651283Y115710D01*
X653505D01*
X654330Y116535D01*
G01X657480Y125984D02*
X655905Y124409D01*
X653448D01*
X652858Y124999D01*
X650834D01*
X650609Y124774D01*
X650522D01*
G01X654331Y125984D02*
X654096Y125749D01*
X650834D01*
X650609Y125974D01*
X650522D01*
G01X654330Y129134D02*
Y129361D01*
G03X653358Y130333I-972J0D01*
G01X652636D01*
X651846Y129543D01*
X650243D01*
X648956Y130830D01*
X645179D01*
X644954Y130605D01*
X644867D01*
G01Y131805D02*
X644954D01*
X645179Y131580D01*
X649267D01*
X650554Y130293D01*
X651535D01*
X652325Y131083D01*
X653358D01*
G03X654330Y132055I0J972D01*
G01Y132283D01*
G01Y135433D02*
X652755Y133858D01*
X650273D01*
X649315Y132900D01*
X646987D01*
X645495Y134392D01*
X644740D01*
X644515Y134167D01*
X644428D01*
G01X651181Y135433D02*
X650787D01*
X649004Y133650D01*
X647298D01*
X645806Y135142D01*
X644740D01*
X644515Y135367D01*
X644428D01*
G01X654330Y144882D02*
X652755Y143307D01*
X650503D01*
X650128Y143682D01*
X649487D01*
M02*
